G04 ================== begin FILE IDENTIFICATION RECORD ==================*
G04 Layout Name:  t6m_pdb_d_0928_1400_274.brd*
G04 Film Name:    in1*
G04 File Format:  Gerber RS274X*
G04 File Origin:  Cadence Allegro 16.3-S048*
G04 Origin Date:  Tue Nov 26 11:01:50 2013*
G04 *
G04 Layer:  DRAWING FORMAT/TITLE_BLOCK*
G04 Layer:  VIA CLASS/IN1*
G04 Layer:  PIN/IN1*
G04 Layer:  MANUFACTURING/PHOTOPLOT_OUTLINE*
G04 Layer:  ETCH/IN1*
G04 Layer:  DRAWING FORMAT/TITLE_DATA_IN1*
G04 *
G04 Offset:    (0.00 0.00)*
G04 Mirror:    No*
G04 Mode:      Positive*
G04 Rotation:  0*
G04 FullContactRelief:  No*
G04 UndefLineWidth:     6.00*
G04 ================== end FILE IDENTIFICATION RECORD ====================*
%FSLAX25Y25*MOIN*%
%IR0*IPPOS*OFA0.00000B0.00000*MIA0B0*SFA1.00000B1.00000*%
%ADD11C,.02*%
%ADD12C,.04*%
%ADD15C,.046*%
%ADD14C,.064*%
%ADD10C,.055*%
%ADD13C,.077*%
%ADD16C,.018*%
%ADD17C,.005*%
%ADD18C,.006*%
%ADD19C,.03004*%
%ADD23C,.05004*%
%ADD20C,.06204*%
%ADD31C,.07404*%
%ADD29C,.05604*%
%ADD22C,.06504*%
%ADD32C,.08704*%
%ADD21C,.10304*%
%ADD24C,.10504*%
%ADD34C,.24502*%
%ADD26C,.40406*%
%ADD30C,.13238*%
%ADD27C,.16406*%
%ADD33C,.13266*%
%ADD28C,.35606*%
%ADD25C,.15806*%
G75*
%LPD*%
G75*
G36*
G01X36618Y743092D02*
X37030Y742681D01*
Y700925D01*
X74720Y663235D01*
Y520526D01*
X34858Y480665D01*
Y451039D01*
X55204Y430694D01*
Y429824D01*
G02X53858Y428886I-1000J0D01*
G03Y422782I-1123J-3052D01*
G02X55204Y421844I346J-938D01*
G01Y413923D01*
X41172Y399891D01*
Y260526D01*
X52955Y248742D01*
G02X52362Y247042I-707J-707D01*
G03X55966Y243438I373J-3231D01*
G02X57666Y244031I993J-114D01*
G01X65162Y236536D01*
Y188563D01*
G02X63463Y187847I-1000J0D01*
G03Y176105I-5728J-5871D01*
G02X65162Y175389I699J-716D01*
G01Y161308D01*
X35882Y132029D01*
Y49870D01*
X24196Y38184D01*
G02X23695Y38060I-353J354D01*
G03X23834Y31892I-960J-3107D01*
G02X24356Y31775I169J-470D01*
G02Y31068I-353J-354D01*
G01X23882Y30594D01*
X21606D01*
X19196Y28184D01*
G02X18695Y28060I-353J354D01*
G03X15598Y22501I-960J-3107D01*
G02X14941Y20748I-657J-753D01*
G01X5948D01*
G02X4999Y21684I-43J906D01*
G01X5000Y21701D01*
Y53683D01*
G02X6731Y54364I1000J-1D01*
G03Y65542I6004J5589D01*
G02X5000Y66223I-731J682D01*
G01Y175706D01*
G02X6731Y176387I1000J-1D01*
G03Y187565I6004J5589D01*
G02X5000Y188246I-731J682D01*
G01Y262541D01*
G02X6731Y263222I1000J-1D01*
G03Y274400I6004J5589D01*
G02X5000Y275081I-731J682D01*
G01Y384564D01*
G02X6731Y385245I1000J-1D01*
G03Y396423I6004J5589D01*
G02X5000Y397104I-731J682D01*
G01Y522892D01*
G02X5499Y523392I500J0D01*
G03Y533696I-8J5152D01*
G01Y596689D01*
G02X6203Y596952I401J0D01*
G03X13221Y597216I3403J2949D01*
G02X13865I322J-239D01*
G03Y602586I3615J2685D01*
G02X13221I-322J239D01*
G03X6203Y602850I-3615J-2685D01*
G02X5499Y603113I-303J263D01*
G01Y624052D01*
G02X6203Y624315I401J0D01*
G03X13221Y624579I3403J2949D01*
G02X13865I322J-239D01*
G03Y629949I3615J2685D01*
G02X13221I-322J239D01*
G03X6203Y630213I-3615J-2685D01*
G02X5499Y630476I-303J263D01*
G01Y716964D01*
G02X6477Y716977I501J-865D01*
G03Y721373I1196J2198D01*
G02X5499Y721386I-477J878D01*
G01Y724838D01*
G02X6477Y724851I501J-865D01*
G03Y729247I1196J2198D01*
G02X5499Y729260I-477J878D01*
G01Y732712D01*
G02X6477Y732725I501J-865D01*
G03Y737121I1196J2198D01*
G02X5499Y737134I-477J878D01*
G01Y740586D01*
G02X6477Y740599I501J-865D01*
G03Y744995I1196J2198D01*
G02X5499Y745008I-477J878D01*
G01Y748460D01*
G02X6477Y748473I501J-865D01*
G03Y752869I1196J2198D01*
G02X5499Y752882I-477J878D01*
G01Y756334D01*
G02X6477Y756347I501J-865D01*
G03X9956Y757521I1196J2198D01*
G02X11575Y757818I912J-410D01*
G01X12767Y756626D01*
X12957D01*
G02X13457Y756126I0J-500D01*
G01Y755990D01*
X13388Y755873D01*
G03X17204Y752734I2159J-1265D01*
G02X18574Y752691I662J-750D01*
G01X23096Y748169D01*
X23154Y747868D01*
X23092Y747726D01*
G03X27658Y745681I2297J-992D01*
G02X29273Y745967I907J-421D01*
G01X30307Y744932D01*
X30746D01*
G02X31246Y744432I0J-500D01*
G01Y744284D01*
X31165Y744160D01*
G03X35765Y742748I2098J-1363D01*
G01X35768Y742950D01*
X35911Y743092D01*
G02X36618I353J-353D01*
G37*
G36*
G01X104331Y2004D02*
G02X100429Y5906I0J3902D01*
G01Y9843D01*
G03X92520Y17752I-7909J0D01*
G01X5906D01*
G02X2004Y21654I0J3902D01*
G01Y522387D01*
X3998D01*
Y21711D01*
G03X5905Y19745I1908J-58D01*
G01X5906D01*
Y19746D01*
X91602D01*
Y19745D01*
X92520D01*
G02X102422Y9843I-1J-9903D01*
G01Y5906D01*
G03X104330Y3997I1908J-1D01*
G01X104331D01*
Y3998D01*
X397638D01*
G03X401514Y7874I0J3876D01*
G01Y1915529D01*
X401515D01*
Y1915541D01*
X401514Y1915551D01*
Y2078740D01*
G03X397638Y2082616I-3876J0D01*
G01X104331D01*
Y2082617D01*
X104330D01*
G03X102422Y2080709I0J-1908D01*
G01Y2076772D01*
G02X99522Y2069769I-9903J-1D01*
G02X92520Y2066868I-7003J7002D01*
G01X5964D01*
G03X4556Y2066310I-59J-1907D01*
G03X3998Y2064961I1350J-1348D01*
G01Y1608989D01*
G02X3498Y1608489I-500J0D01*
G01X2504D01*
G02X2004Y1608989I0J500D01*
G01Y2064961D01*
G02X5905Y2068862I3901J0D01*
G01X92520D01*
G03X100429Y2076772I0J7909D01*
G01Y2080709D01*
G02X104331Y2084610I3902J-1D01*
G01X397638D01*
G02X403508Y2078740I0J-5870D01*
G01Y7874D01*
G02X397638Y2004I-5870J0D01*
G01X104331D01*
G37*
G36*
G01X2004Y534555D02*
Y1596934D01*
G02X2504Y1597434I500J0D01*
G01X3498D01*
G02X3998Y1596934I0J-500D01*
G01Y1143740D01*
X3610Y1143352D01*
Y1138186D01*
X3998Y1137798D01*
Y534555D01*
X2004D01*
G37*
G36*
G01X104373Y5000D02*
G02X103705Y5249I-43J906D01*
G02X103424Y5936I625J657D01*
G01Y9843D01*
G03X96772Y19883I-10904J-1D01*
G03X92604Y20746I-4252J-10041D01*
G01Y20748D01*
X50529D01*
G02X49872Y22501I0J1000D01*
G03X49253Y27829I-2137J2452D01*
G02X48986Y28271I233J442D01*
G01Y31741D01*
G02X50617Y32485I1000J-32D01*
G03X52726Y31701I2118J2468D01*
G03X54253Y37829I9J3252D01*
G02X53986Y38271I233J442D01*
G01Y46034D01*
X45903Y54118D01*
X44886Y55135D01*
Y105403D01*
G02X46783Y105844I1000J0D01*
G03X65354Y94272I18571J9116D01*
G03X86042Y114960I0J20688D01*
G03X65402Y135648I-20688J0D01*
G01X65400D01*
X65352Y135647D01*
X65350D01*
G03X51526Y130347I3J-20687D01*
G03X46783Y124076I13827J-15387D01*
G02X44886Y124516I-897J441D01*
G01Y128297D01*
X74164Y157576D01*
Y240268D01*
X55383Y259050D01*
G02X56242Y260746I707J707D01*
G03X65585Y271189I1493J8065D01*
G03X51887Y274563I-7850J-2378D01*
G02X50174Y275233I-713J701D01*
G01Y384412D01*
G02X51887Y385082I1000J-31D01*
G03X59558Y382837I5847J5752D01*
G03X65795Y389309I-1822J7998D01*
G03X56292Y398909I-8060J1525D01*
G02X55409Y400600I-176J984D01*
G01X56392Y401583D01*
X64206Y409398D01*
Y434426D01*
X43862Y454771D01*
Y457863D01*
G02X45806Y458190I1000J-1D01*
G03X65355Y444272I19549J6770D01*
G03X86043Y464960I0J20688D01*
G03X45806Y471730I-20688J0D01*
G02X43862Y472057I-944J328D01*
G01Y476934D01*
X83722Y516795D01*
Y665478D01*
G02X85404Y666178I1000J-32D01*
G01X88429Y663153D01*
G02X88576Y662800I-353J-354D01*
G01Y420034D01*
X84764Y416222D01*
Y358452D01*
X92609Y350606D01*
X93596Y349619D01*
Y101120D01*
X106672Y88044D01*
G02X106464Y86471I-707J-707D01*
G03X108515Y84420I749J-1302D01*
G02X110088Y84628I866J-499D01*
G01X113105Y81611D01*
G02X113252Y81279I-352J-355D01*
G01Y72970D01*
X115990Y70231D01*
X116327Y69894D01*
G02X116466Y69452I-353J-354D01*
G01X116449Y69360D01*
X116435Y69321D01*
G03X118670Y71556I3485J-1250D01*
G01X118631Y71542D01*
X118539Y71525D01*
G02X118097Y71664I-88J492D01*
G01X115901Y73860D01*
G02X115754Y74192I352J355D01*
G01Y74626D01*
G02X117407Y75352I1000J-32D01*
G03X123253Y79683I2513J2718D01*
G02X124156Y81112I903J429D01*
G01X126787D01*
X128820Y79079D01*
Y67389D01*
X136331Y59878D01*
G02X136447Y59352I-353J-354D01*
G03X142567Y55483I3473J-1281D01*
G03X138624Y61539I-2647J2588D01*
G01X138486Y61487D01*
X138200Y61549D01*
X131324Y68425D01*
Y80115D01*
X127823Y83616D01*
X123109D01*
G02X122431Y85350I0J1000D01*
G03X118542Y91507I-2510J2721D01*
G03X118257Y84763I1378J-3436D01*
G03X118669Y84587I1658J3310D01*
G02X119000Y84116I-169J-471D01*
G02X118500Y83616I-500J0D01*
G01X117290D01*
X97545Y103361D01*
G02X97416Y103674I371J336D01*
G01Y226348D01*
X97417Y348999D01*
G02X99099Y349731I1000J1D01*
G01X110596Y338234D01*
X202377D01*
X291887Y248724D01*
G02X292016Y248411I-371J-336D01*
G01Y235440D01*
X316221Y211234D01*
X322215D01*
X326222Y207227D01*
Y195329D01*
X330023Y191528D01*
G02X330152Y191215I-371J-336D01*
G01Y52249D01*
X330089Y52136D01*
G03Y50682I1314J-727D01*
G01X330152Y50569D01*
Y22255D01*
X338481Y13926D01*
X358155D01*
X361070Y16840D01*
G02X361536Y16974I354J-353D01*
G03X359408Y20209I629J2731D01*
G01X359375Y20030D01*
X359098Y19799D01*
X358916D01*
G02X358416Y20299I0J500D01*
G01Y21906D01*
G02X358651Y22330I500J0D01*
G03X359794Y25675I-1486J2376D01*
G03X357669Y27462I-2629J-969D01*
G01X357490Y27495D01*
X357259Y27772D01*
Y27954D01*
G02X357759Y28454I500J0D01*
G01X359366D01*
G02X359790Y28219I0J-500D01*
G03Y31191I2375J1486D01*
G02X359366Y30956I-424J265D01*
G01X358097D01*
G02X357742Y31103I-1J500D01*
G01X357687Y31159D01*
X357677Y31169D01*
G02X357683Y31876I357J350D01*
G01X357776Y31967D01*
X357902Y32002D01*
G03X359965Y34802I-737J2703D01*
G03X356536Y37436I-2800J-97D01*
G02X356070Y37570I-112J487D01*
G01X349686Y43953D01*
G02X349540Y44306I354J353D01*
G01Y50023D01*
X349603Y50136D01*
G03Y51590I-1314J727D01*
G01X349540Y51703D01*
Y57470D01*
X339368Y67642D01*
Y191386D01*
G02X340819Y192247I1000J-32D01*
G03X343521Y192253I1346J2458D01*
G03X344962Y194530I-1356J2452D01*
G01X344974Y194719D01*
X345108Y194853D01*
G02X345815I353J-354D01*
G01X346006Y194662D01*
X348908D01*
G02X349399Y194256I0J-500D01*
G03X354657Y193425I2766J449D01*
G03X350922Y197216I-2492J1280D01*
G01X350818Y197164D01*
X350609D01*
G02X349727Y198570I32J1000D01*
G03X349901Y200313I-2562J1136D01*
G01X349896Y200334D01*
Y200335D01*
G02X350029Y200800I487J112D01*
G01X350070Y200841D01*
Y201096D01*
G02X351339Y202027I1000J-32D01*
G03X353651Y207080I826J2677D01*
G02X353416Y207504I265J424D01*
G01Y209111D01*
G02X353916Y209611I500J0D01*
G01X354098D01*
X354375Y209380D01*
X354408Y209201D01*
G03X355139Y211641I2757J504D01*
G02X353416Y212300I-723J691D01*
G01Y215065D01*
X350774Y217708D01*
X350442Y218040D01*
Y226942D01*
X331410Y245974D01*
X331374Y246098D01*
G03X330344Y247128I-1444J-414D01*
G01X330220Y247164D01*
X218806Y358578D01*
X122423D01*
X120203Y360798D01*
G02X120687Y362480I707J707D01*
G03X122724Y368519I-767J3622D01*
G03X117084Y368482I-2804J-2417D01*
G02X115318Y369093I-766J643D01*
G01Y373111D01*
G02X117084Y373722I1000J-32D01*
G03Y378482I2836J2380D01*
G02X115318Y379093I-766J643D01*
G01Y383111D01*
G02X117084Y383722I1000J-32D01*
G03Y388482I2836J2380D01*
G02X115318Y389093I-766J643D01*
G01Y393990D01*
X115173Y394135D01*
G02Y394842I354J354D01*
G01X115217Y394886D01*
X115270Y394918D01*
G03X115538Y395123I-773J1288D01*
G03X115568Y395153I-1047J1077D01*
G02X116400Y394957I356J-351D01*
G03X123601Y395711I3520J1146D01*
G03X117454Y398863I-3681J391D01*
G03X117422Y398834I2470J-2758D01*
G02X115750Y399574I-672J740D01*
G01Y402630D01*
G02X117422Y403370I1000J0D01*
G03Y408834I2498J2732D01*
G02X115750Y409574I-672J740D01*
G01Y412003D01*
X117066Y413319D01*
X117448Y413339D01*
X117597Y413219D01*
G03X123595Y415655I2323J2883D01*
G03X118442Y419496I-3675J447D01*
G02X117054Y420386I-388J922D01*
G01Y421818D01*
G02X118442Y422708I1000J-32D01*
G03Y429496I1478J3394D01*
G02X117054Y430386I-388J922D01*
G01Y431818D01*
G02X118442Y432708I1000J-32D01*
G03X123600Y436502I1478J3394D01*
G03X117836Y439162I-3680J-400D01*
G02X117054Y439575I-282J413D01*
G01Y440138D01*
X115316Y441876D01*
Y443113D01*
G02X117072Y443737I1000J-31D01*
G03Y448467I2848J2365D01*
G02X115316Y449091I-756J655D01*
G01Y453113D01*
G02X117072Y453737I1000J-31D01*
G03Y458467I2848J2365D01*
G02X115316Y459091I-756J655D01*
G01Y463113D01*
G02X117072Y463737I1000J-31D01*
G03Y468467I2848J2365D01*
G02X115316Y469091I-756J655D01*
G01Y473113D01*
G02X117072Y473737I1000J-31D01*
G03Y478467I2848J2365D01*
G02X115316Y479091I-756J655D01*
G01Y483113D01*
G02X117072Y483737I1000J-31D01*
G03Y488467I2848J2365D01*
G02X115316Y489091I-756J655D01*
G01Y493113D01*
G02X117072Y493737I1000J-31D01*
G03Y498467I2848J2365D01*
G02X115316Y499091I-756J655D01*
G01Y503113D01*
G02X117072Y503737I1000J-31D01*
G03Y508467I2848J2365D01*
G02X115316Y509091I-756J655D01*
G01Y513113D01*
G02X117072Y513737I1000J-31D01*
G03Y518467I2848J2365D01*
G02X115316Y519091I-756J655D01*
G01Y523113D01*
G02X117072Y523737I1000J-31D01*
G03Y528467I2848J2365D01*
G02X115316Y529091I-756J655D01*
G01Y533113D01*
G02X117072Y533737I1000J-31D01*
G03Y538467I2848J2365D01*
G02X115316Y539091I-756J655D01*
G01Y543113D01*
G02X117072Y543737I1000J-31D01*
G03Y548467I2848J2365D01*
G02X115316Y549091I-756J655D01*
G01Y553113D01*
G02X117072Y553737I1000J-31D01*
G03Y558467I2848J2365D01*
G02X115316Y559091I-756J655D01*
G01Y674663D01*
X80134Y709846D01*
Y710693D01*
G02X80988Y711046I500J0D01*
G01X101148Y690886D01*
X229560D01*
X302570Y617876D01*
Y579671D01*
X318901Y563340D01*
X320241D01*
X325523Y558058D01*
G02X325652Y557745I-371J-336D01*
G01Y539935D01*
X328299Y537287D01*
X328632Y536954D01*
Y454383D01*
X319728Y445479D01*
Y424065D01*
X319666Y423952D01*
G03Y422498I1314J-727D01*
G01X319728Y422385D01*
Y402747D01*
X326623Y395852D01*
G02X326752Y395539I-371J-336D01*
G01Y372835D01*
X338188Y361398D01*
X362210D01*
X362831Y362019D01*
X367768Y366957D01*
Y371585D01*
X363397Y375956D01*
X362759D01*
G02X362259Y376456I0J500D01*
G01Y376638D01*
X362490Y376915D01*
X362669Y376948D01*
G03X364794Y378735I-504J2756D01*
G03X363651Y382080I-2629J969D01*
G02X363416Y382504I265J424D01*
G01Y384563D01*
X359190Y388790D01*
X358658Y389322D01*
X356229D01*
X343577Y401974D01*
X343541Y402098D01*
G03X342511Y403128I-1444J-414D01*
G01X342387Y403164D01*
X335086Y410465D01*
Y447808D01*
X337844Y450566D01*
Y540771D01*
X335009Y543606D01*
G02X334862Y543938I352J355D01*
G01Y546165D01*
G02X336197Y547076I1000J-32D01*
G03X339687Y548482I969J2629D01*
G02X341259Y548759I891J-455D01*
G01X341565Y548454D01*
X341572D01*
G02X342072Y547954I0J-500D01*
G01Y547772D01*
X341841Y547495D01*
X341662Y547462D01*
G03X342670I504J-2757D01*
G01X342491Y547495D01*
X342260Y547772D01*
Y547954D01*
G02X342760Y548454I500J0D01*
G01X344367D01*
G02X344791Y548219I0J-500D01*
G03X349906Y549118I2375J1486D01*
G01X349937Y549262D01*
X350019Y549345D01*
G02X350727Y549346I354J-353D01*
G01X350884Y549189D01*
Y547485D01*
G02X350654Y547064I-500J0D01*
G03X353678I1512J-2359D01*
G02X353448Y547485I270J421D01*
G01Y549108D01*
G02X353948Y549608I500J0D01*
G01X354100D01*
X354377Y549377D01*
X354410Y549199D01*
G03X354468Y550464I2756J507D01*
G02X354136Y550122I-481J135D01*
G01X353720Y549992D01*
X353448Y550059D01*
Y550251D01*
X352941Y550757D01*
G02X353344Y552162I858J514D01*
G03X354267Y556559I-1178J2543D01*
G03X353653Y557080I-2101J-1854D01*
G02X353418Y557504I265J424D01*
G01Y557758D01*
X351893Y559283D01*
G02X351746Y559615I352J355D01*
G01Y561208D01*
X337563Y575392D01*
G02X337609Y576850I707J707D01*
G03X335489Y578970I-992J1128D01*
G02X334031Y578924I-751J661D01*
G01X330707Y582248D01*
G02X330696Y583651I707J707D01*
G03X328572Y585775I-1060J1064D01*
G02X327169Y585786I-696J718D01*
G01X325149Y587806D01*
G02X325002Y588138I352J355D01*
G01Y588315D01*
X325065Y588428D01*
G03Y589882I-1314J727D01*
G01X325002Y589995D01*
Y622800D01*
X239470Y708332D01*
X121858D01*
G02X121526Y708479I23J499D01*
G01X120948Y709057D01*
G02X121286Y710693I707J707D01*
G03X123169Y715908I-1366J3441D01*
G03X121682Y717390I-3250J-1773D01*
G03X116283Y714827I-1762J-3256D01*
G01X116254Y714675D01*
X116146Y714567D01*
G02X115438I-354J353D01*
G01X114836Y715169D01*
Y739623D01*
X112054Y742405D01*
Y766629D01*
G02X112949Y767624I1000J1D01*
G03Y770620I-113J1498D01*
G02X112054Y771615I105J994D01*
G01Y791875D01*
G02X113286Y792848I1000J0D01*
G03Y795738I411J1445D01*
G02X112054Y796711I-232J973D01*
G01Y913205D01*
X48268Y976990D01*
X36579D01*
G02X35655Y978284I32J1000D01*
G03X34806Y980988I-2392J734D01*
G01X34720Y981056D01*
X34514Y981456D01*
Y986997D01*
G02X34660Y987350I500J0D01*
G01X51118Y1003807D01*
Y1010421D01*
X58507Y1017810D01*
G02X59755Y1017945I708J-707D01*
G03X61888Y1017957I1060J1081D01*
G01X61916Y1017985D01*
X62243Y1018122D01*
X62571Y1017997D01*
X62632Y1017947D01*
G03X65073Y1019252I945J1168D01*
G03X62564Y1020224I-1496J-137D01*
G01X62500Y1020165D01*
X62149Y1020019D01*
X61847Y1020134D01*
X61820Y1020158D01*
G03X61664Y1020279I-1004J-1133D01*
G01X61649Y1020289D01*
X61524Y1020414D01*
Y1020828D01*
X61672Y1020975D01*
X67707Y1027010D01*
X166696D01*
X166865Y1026841D01*
X168213Y1025494D01*
X173476D01*
G02X174428Y1024308I-31J-1000D01*
G03X176330Y1022559I1469J-311D01*
G03X177200Y1024745I-433J1438D01*
G01X177134Y1024860D01*
Y1024994D01*
G02X177634Y1025494I500J0D01*
G01X178383D01*
X182451Y1021426D01*
X182977D01*
G02X183477Y1020926I0J-500D01*
G01Y1020802D01*
X183364Y1020585D01*
X183262Y1020515D01*
G03X184974I856J-1235D01*
G01X184872Y1020585D01*
X184759Y1020802D01*
Y1020926D01*
G02X185259Y1021426I500J0D01*
G01X185944D01*
G02X186899Y1020592I-32J-1000D01*
G03X189871I1486J218D01*
G02X190826Y1021426I987J-166D01*
G01X254409D01*
G02X254722Y1021297I-23J-500D01*
G01X307060Y968959D01*
Y927518D01*
X325266Y909311D01*
Y851344D01*
X330439Y846171D01*
G02X330568Y845858I-371J-336D01*
G01Y798349D01*
G02X330422Y797996I-500J0D01*
G01X326736Y794311D01*
X326272Y793847D01*
Y758860D01*
X326210Y758747D01*
G03Y757293I1314J-727D01*
G01X326272Y757180D01*
Y722798D01*
X335890Y713180D01*
X357411D01*
X361071Y716840D01*
G02X361537Y716974I354J-353D01*
G03X363688Y722058I630J2731D01*
G01Y727327D01*
X363762Y727401D01*
X363776Y727411D01*
G03X363653Y732080I-1607J2294D01*
G02X363418Y732504I265J424D01*
G01Y734537D01*
X356961Y740994D01*
X356694D01*
X345589Y752099D01*
X345553Y752223D01*
G03X344523Y753253I-1444J-414D01*
G01X344399Y753289D01*
X340611Y757077D01*
G02X340482Y757390I371J336D01*
G01Y850498D01*
X335204Y855776D01*
Y896058D01*
G02X336447Y896997I1000J-32D01*
G03Y902413I718J2708D01*
G02X335204Y903352I-243J971D01*
G01Y906058D01*
G02X336447Y906997I1000J-32D01*
G03X339778Y908694I718J2708D01*
G01X339816Y908792D01*
X339891Y908867D01*
G02X340599I354J-353D01*
G01X340878Y908587D01*
Y907482D01*
G02X340649Y907061I-500J-1D01*
G03X340142Y902766I1516J-2356D01*
G03X344891Y904059I2023J1939D01*
G02X345377Y904443I486J-116D01*
G01X345378D01*
G02X345878Y903943I0J-500D01*
G01Y902482D01*
G02X345649Y902061I-500J-1D01*
G03X345142Y897766I1516J-2356D01*
G03X349805Y898766I2023J1939D01*
G01X349858Y898915D01*
X350117Y899098D01*
X350276D01*
G02X350776Y898598I0J-500D01*
G01Y897414D01*
X350564Y897008D01*
X350475Y896941D01*
G03X353709Y897044I1690J-2236D01*
G02X353484Y897462I275J418D01*
G01Y898819D01*
G02X353984Y899319I500J0D01*
G02X354466Y898953I0J-500D01*
G03X354686Y901010I2699J752D01*
G02X353094Y900768I-885J466D01*
G01X352894Y900968D01*
G02X353387Y902183I946J324D01*
G03X354281Y902868I-1223J2521D01*
G03X353622Y907099I-2116J1837D01*
G01X353510Y907167D01*
X353382Y907395D01*
Y909351D01*
G02X353882Y909851I500J0D01*
G01X354074D01*
X354359Y909595D01*
X354379Y909405D01*
G03X359940Y909320I2786J300D01*
G03X355503Y911961I-2775J385D01*
G03X355108Y911607I1664J-2254D01*
G02X353382Y912295I-726J688D01*
G01Y914360D01*
X341089Y926653D01*
X341076Y926708D01*
G03X340989Y926965I-1461J-351D01*
G03X340929Y927084I-1370J-616D01*
G01X340866Y927197D01*
Y940262D01*
X337076Y944052D01*
Y969284D01*
X262479Y1043882D01*
G02X263179Y1045564I732J682D01*
G01X345067D01*
X345868Y1046364D01*
X345992Y1046400D01*
G03X347022Y1047430I-414J1444D01*
G01X347058Y1047554D01*
X366846Y1067343D01*
Y1072153D01*
X363043Y1075956D01*
X362759D01*
G02X362259Y1076456I0J500D01*
G01Y1076638D01*
X362490Y1076915D01*
X362669Y1076948D01*
G03X364794Y1078735I-504J2756D01*
G03X363651Y1082080I-2629J969D01*
G02X363416Y1082504I265J424D01*
G01Y1085280D01*
X354064Y1094632D01*
X334690D01*
X330634Y1090577D01*
X330124Y1090067D01*
Y1072714D01*
X314136Y1056726D01*
X87858D01*
X84243Y1060341D01*
X84207Y1060465D01*
G03X83177Y1061495I-1444J-414D01*
G01X83053Y1061531D01*
X52779Y1091804D01*
X44479D01*
G02X44166Y1091933I23J500D01*
G01X35878Y1100221D01*
G02X35733Y1100615I353J354D01*
G01X35736Y1100656D01*
X35739Y1100675D01*
G03X33654Y1098590I-2472J387D01*
G01X33673Y1098593D01*
X33714Y1098596D01*
G02X34108Y1098451I40J-498D01*
G01X41443Y1091116D01*
G02X40743Y1089434I-732J-682D01*
G01X35061D01*
G02X34706Y1089581I-1J500D01*
G01X34639Y1089649D01*
X34631Y1089657D01*
G02X34747Y1091170I707J707D01*
G03X31249Y1094668I-1480J2018D01*
G02X29736Y1094552I-806J591D01*
G01X28002Y1096286D01*
G02X27862Y1096720I353J354D01*
G03X25798Y1094656I-2469J405D01*
G02X26232Y1094516I80J-493D01*
G01X31903Y1088845D01*
G02X31787Y1087332I-707J-707D01*
G03X31249Y1086794I1480J-2018D01*
G02X29736Y1086678I-806J591D01*
G01X28002Y1088412D01*
G02X27862Y1088846I353J354D01*
G03X25780Y1086779I-2469J405D01*
G01X25799Y1086782D01*
X25840Y1086785D01*
G02X26234Y1086640I40J-498D01*
G01X28564Y1084310D01*
G02X27864Y1082628I-732J-682D01*
G01X27832D01*
G02X27438Y1082819I-1J500D01*
G03X26963Y1083325I-2044J-1443D01*
G03X22993Y1080670I-1570J-1948D01*
G02X22023Y1079424I-969J-246D01*
G01X19274D01*
X18160Y1080538D01*
G02X18020Y1080972I353J354D01*
G03X18023Y1080992I-2473J381D01*
G03X13533Y1082857I-2472J385D01*
G02X12020Y1082741I-806J591D01*
G01X10286Y1084475D01*
G02X10146Y1084909I353J354D01*
G03X6456Y1087498I-2469J405D01*
G02X5000Y1088388I-456J890D01*
G01Y1090114D01*
G02X6456Y1091004I1000J0D01*
G03Y1095372I1221J2184D01*
G02X5000Y1096262I-456J890D01*
G01Y1097988D01*
G02X6456Y1098878I1000J0D01*
G03Y1103246I1221J2184D01*
G02X5000Y1104136I-456J890D01*
G01Y1105862D01*
G02X6456Y1106752I1000J0D01*
G03Y1111120I1221J2184D01*
G02X5000Y1112010I-456J890D01*
G01Y1113736D01*
G02X6456Y1114626I1000J0D01*
G03Y1118994I1221J2184D01*
G02X5000Y1119884I-456J890D01*
G01Y1121610D01*
G02X6456Y1122500I1000J0D01*
G03X9217Y1122712I1221J2184D01*
G03X9709Y1123224I-1540J1972D01*
G02X10115Y1123432I406J-292D01*
G01X12481D01*
G02X13357Y1121951I0J-1000D01*
G03X15866Y1118266I2194J-1203D01*
G03X15938Y1118276I-308J2483D01*
G01X15957Y1118279D01*
X15998Y1118282D01*
G02X16392Y1118137I40J-498D01*
G01X16743Y1117786D01*
X19552Y1114978D01*
X22101D01*
G02X23026Y1113683I-31J-1000D01*
G03X27760I2367J-810D01*
G02X28685Y1114978I956J295D01*
G01X29141D01*
X29708Y1115545D01*
G02X31204Y1115394I682J-732D01*
G03X32156Y1114568I2063J1416D01*
G03X35658Y1117548I1111J2242D01*
G02X36613Y1118842I955J294D01*
G01X37500D01*
X39474Y1120816D01*
X83191D01*
X113828Y1151453D01*
Y1371000D01*
X114441Y1371613D01*
X119315Y1376488D01*
G02X119668Y1376634I353J-354D01*
G01X169931D01*
X178053Y1368512D01*
X233598D01*
G02X233911Y1368383I-23J-500D01*
G01X320498Y1281796D01*
X320534Y1281672D01*
G03X321564Y1280642I1444J414D01*
G01X321688Y1280606D01*
X335785Y1266509D01*
G02X335914Y1266196I-371J-336D01*
G01Y1262504D01*
G02X335679Y1262080I-500J0D01*
G03X334400Y1259249I1486J-2376D01*
G03X339151Y1257728I2765J456D01*
G02X340460Y1257822I709J-706D01*
G01X340793Y1257489D01*
Y1257242D01*
X340536Y1256985D01*
X340505Y1256963D01*
G03X341976Y1251909I1660J-2258D01*
G01X342164Y1251897D01*
X342656Y1251403D01*
Y1248007D01*
X342164Y1247513D01*
X341976Y1247501D01*
G03X339752Y1243281I189J-2796D01*
G03X344760Y1243647I2413J1424D01*
G02X346393Y1243977I926J-377D01*
G01X346452Y1243919D01*
X346917Y1243454D01*
X349366D01*
G02X349790Y1243219I0J-500D01*
G03Y1246191I2375J1486D01*
G02X349366Y1245956I-424J265D01*
G01X347954D01*
X347730Y1246180D01*
G02Y1246887I354J353D01*
G01X347821Y1246978D01*
X347945Y1247014D01*
G03X348651Y1252080I-780J2691D01*
G02X348416Y1252504I265J424D01*
G01Y1254111D01*
G02X348916Y1254611I500J0D01*
G01X349098D01*
X349375Y1254380D01*
X349408Y1254201D01*
G03X353879Y1252488I2757J504D01*
G03X353651Y1257080I-1714J2217D01*
G02X353416Y1257504I265J424D01*
G01Y1259111D01*
G02X353916Y1259611I500J0D01*
G01X354098D01*
X354375Y1259380D01*
X354408Y1259201D01*
G03X355139Y1261641I2757J504D01*
G02X353416Y1262300I-723J691D01*
G01Y1268999D01*
X339527Y1282889D01*
X339491Y1283013D01*
G03X338461Y1284043I-1444J-414D01*
G01X338337Y1284079D01*
X299764Y1322652D01*
G02X300783Y1324309I707J707D01*
G03X287893Y1337199I6304J19194D01*
G02X286236Y1336180I-950J-312D01*
G01X235604Y1386812D01*
X117125D01*
G02X116770Y1387664I0J500D01*
G01X116789Y1387683D01*
X116932Y1387827D01*
G02X117287Y1387974I354J-353D01*
G01X172112D01*
X181226Y1397088D01*
X321580D01*
X322734Y1398241D01*
X322879Y1398386D01*
G02X324390Y1398275I708J-707D01*
G03X326908Y1398316I1246J839D01*
G02X328449Y1398470I833J-553D01*
G01X328604Y1398316D01*
X329832Y1397088D01*
X341317D01*
X344074Y1399844D01*
X344420Y1400190D01*
X344544Y1400226D01*
G03X345574Y1401256I-414J1444D01*
G01X345610Y1401380D01*
X347559Y1403329D01*
G02X349235Y1402870I707J-707D01*
G03X351063Y1404698I1455J373D01*
G02X350604Y1406374I248J969D01*
G01X361070Y1416840D01*
G02X361536Y1416974I354J-353D01*
G03X362636Y1422467I630J2731D01*
G01X362469Y1422495D01*
Y1426915D01*
X362636Y1426943D01*
G03X363651Y1432080I-471J2762D01*
G02X363416Y1432504I265J424D01*
G01Y1435877D01*
X358289Y1441005D01*
X357644Y1441650D01*
X334463D01*
X328342Y1435529D01*
Y1419479D01*
X324857Y1415994D01*
X173394D01*
X158328Y1400928D01*
X158204Y1400892D01*
G03X157174Y1399862I414J-1444D01*
G01X157138Y1399738D01*
X155932Y1398532D01*
X155846D01*
X154610Y1397296D01*
X154266D01*
G02X153566Y1398978I32J1000D01*
G01X156473Y1401886D01*
X156836Y1402248D01*
Y1421987D01*
G02X158557Y1422679I1000J0D01*
G03X169537Y1424767I4828J4526D01*
G03X162593Y1433775I-6152J2438D01*
G02X161766Y1435475I-120J993D01*
G01X182638Y1456348D01*
Y1476932D01*
X264528Y1558822D01*
X282614D01*
G02X283570Y1557977I-32J-1000D01*
G03X286538I1484J234D01*
G02X287494Y1558822I988J-155D01*
G01X287676D01*
G02X288176Y1558322I0J-500D01*
G01Y1558308D01*
X288175Y1558294D01*
G03X291159Y1557977I1500J-83D01*
G02X292115Y1558822I988J-155D01*
G01X292393D01*
G02X292893Y1558322I0J-500D01*
G01Y1558308D01*
X292892Y1558294D01*
G03X295876Y1557977I1500J-83D01*
G02X296832Y1558822I988J-155D01*
G01X296871D01*
G02X297371Y1558322I0J-500D01*
G01Y1558308D01*
X297370Y1558294D01*
G03X300354Y1557977I1500J-83D01*
G02X301310Y1558822I988J-155D01*
G01X327379D01*
X333052Y1564494D01*
X333764Y1565206D01*
X333888Y1565242D01*
G03X334918Y1566272I-414J1444D01*
G01X334954Y1566396D01*
X340385Y1571827D01*
G02X342015Y1571503I707J-707D01*
G03X343979Y1573467I1387J577D01*
G02X343655Y1575097I383J923D01*
G01X359890Y1591333D01*
Y1591920D01*
G02X360659Y1592342I500J0D01*
G03X361819Y1591924I1507J2363D01*
G03X364606Y1596080I346J2781D01*
G03X362437Y1597494I-2442J-1375D01*
G02X361534Y1598489I97J995D01*
G01Y1600921D01*
G02X362437Y1601916I1000J0D01*
G03X362394Y1607498I-271J2789D01*
G02X361476Y1608494I82J996D01*
G01Y1612294D01*
X361224Y1612546D01*
X359219Y1614550D01*
X340241D01*
X338260Y1612570D01*
G02X337794Y1612436I-354J353D01*
G03X335511Y1607443I-630J-2731D01*
G03X335829Y1607242I1653J2263D01*
G02X336047Y1605662I-489J-872D01*
G01X330142Y1599757D01*
Y1595706D01*
X311787Y1577351D01*
X311663Y1577315D01*
G03X310633Y1576285I414J-1444D01*
G01X310597Y1576161D01*
X309260Y1574824D01*
X266065D01*
X172412Y1481171D01*
Y1460587D01*
X147688Y1435863D01*
Y1406919D01*
G02X147541Y1406566I-500J1D01*
G01X146285Y1405310D01*
X98039D01*
X86694Y1393965D01*
G02X85012Y1394665I-682J732D01*
G01Y1461786D01*
G02X85158Y1462139I500J0D01*
G01X111302Y1488282D01*
G02X112612Y1488373I707J-707D01*
G03X114716Y1490477I906J1198D01*
G02X114807Y1491787I798J603D01*
G01X114848Y1491828D01*
X115174Y1492155D01*
Y1719799D01*
G02X115320Y1720152I500J0D01*
G01X122328Y1727159D01*
X123209Y1728040D01*
X167153D01*
X173684Y1734571D01*
X173808Y1734607D01*
G03X174838Y1735637I-414J1444D01*
G01X174874Y1735761D01*
X175919Y1736806D01*
X184238Y1745126D01*
G02X184591Y1745272I353J-354D01*
G01X343989D01*
X367150Y1768433D01*
Y1771354D01*
X363453Y1775052D01*
X362988Y1775517D01*
G02X363272Y1777131I707J708D01*
G03X364861Y1778942I-1107J2574D01*
G03X362496Y1782487I-2696J763D01*
G03X359790Y1781191I-331J-2782D01*
G02X359366Y1780956I-424J265D01*
G01X357759D01*
G02X357259Y1781456I0J500D01*
G01Y1781638D01*
X357490Y1781915D01*
X357669Y1781948D01*
G03X359382Y1786419I-504J2757D01*
G03X354790Y1786191I-2217J-1714D01*
G02X354366Y1785956I-424J265D01*
G01X353695D01*
X349029Y1790622D01*
X335766D01*
X327820Y1782676D01*
X326820Y1781677D01*
Y1771087D01*
X321755Y1766022D01*
X175923D01*
X154241Y1744340D01*
X146852D01*
G02X146120Y1746022I-1J1000D01*
G01X157020Y1756923D01*
Y1771829D01*
G02X158708Y1772524I1000J-32D01*
G03X158707Y1781885I4677J4681D01*
G02X157020Y1782581I-687J728D01*
G01Y1783253D01*
X163183Y1789416D01*
X289215D01*
X337802Y1838003D01*
Y1902754D01*
X343939Y1908891D01*
X344692Y1909643D01*
X344816Y1909679D01*
G03X345846Y1910709I-414J1444D01*
G01X345882Y1910833D01*
X355355Y1920306D01*
G02X356953Y1920053I707J-707D01*
G03X358945Y1922045I1365J627D01*
G02X358692Y1923643I454J891D01*
G01X359530Y1924481D01*
X366192Y1931144D01*
Y1940451D01*
X367188Y1941447D01*
Y1951961D01*
G02X368869Y1952662I1000J-31D01*
G03X367041Y1959456I4516J4858D01*
G02X365378Y1959040I-956J291D01*
G01X364681Y1959737D01*
X359139Y1965278D01*
X340969D01*
X338260Y1962570D01*
G02X337794Y1962436I-354J353D01*
G03X336046Y1957136I-630J-2730D01*
G02X336353Y1955512I-400J-917D01*
G01X335771Y1954930D01*
X331148Y1950306D01*
Y1927627D01*
X331085Y1927514D01*
G03Y1926060I1314J-727D01*
G01X331148Y1925947D01*
Y1918006D01*
X327226Y1914084D01*
Y1841995D01*
X284947Y1799716D01*
X158915D01*
X146720Y1787521D01*
Y1761417D01*
G02X146573Y1761064I-500J1D01*
G01X144929Y1759420D01*
G02X143307Y1759723I-707J707D01*
G03X136599Y1756592I-3387J-1495D01*
G02X135733Y1755150I-897J-442D01*
G01X124107D01*
G02X123241Y1756592I31J1000D01*
G03X117797Y1755195I-3321J1636D01*
G02X117931Y1753669I-573J-819D01*
G01X91292Y1727030D01*
Y1499217D01*
X89224Y1497149D01*
G02X87542Y1497849I-682J732D01*
G01Y1677763D01*
X49031Y1716275D01*
X48974Y1716580D01*
X49037Y1716721D01*
G03X46815Y1714499I-3981J1759D01*
G01X46956Y1714562D01*
X47261Y1714505D01*
X84911Y1676855D01*
G02X85040Y1676542I-371J-336D01*
G01Y1525939D01*
G02X83180Y1525459I-1000J31D01*
G03X82595Y1526396I-17835J-10484D01*
G03X44667Y1514960I-17240J-11436D01*
G03X65355Y1494272I20688J0D01*
G03X81787Y1502392I-1J20687D01*
G03X83184Y1504467I-16431J12570D01*
G02X85040Y1503981I856J-517D01*
G01Y1494922D01*
X47900Y1457782D01*
Y1349075D01*
G02X46218Y1348375I-1000J32D01*
G01X45585Y1349008D01*
X34828D01*
X34456Y1349380D01*
G02X34605Y1350917I707J707D01*
G03X31153Y1354369I-1338J2114D01*
G02X29616Y1354220I-830J558D01*
G01X28906Y1354930D01*
X28737D01*
G02X27775Y1356203I0J1000D01*
G03X23011I-2382J765D01*
G02X22049Y1354930I-962J-273D01*
G01X18895D01*
G02X17933Y1356203I0J1000D01*
G03X16345Y1359341I-2382J765D01*
G03X14342Y1359158I-793J-2373D01*
G03X13523Y1355503I1209J-2190D01*
G01X13567Y1355442D01*
X13621Y1355282D01*
G02X13501Y1354769I-474J-160D01*
G01X13014Y1354282D01*
X10115D01*
X9715Y1354488D01*
X9647Y1354574D01*
G03X8514Y1355389I-1970J-1543D01*
G03X6456Y1355215I-837J-2358D01*
G02X5000Y1356105I-456J890D01*
G01Y1357831D01*
G02X6456Y1358721I1000J0D01*
G03Y1363089I1221J2184D01*
G02X5000Y1363979I-456J890D01*
G01Y1365705D01*
G02X6456Y1366595I1000J0D01*
G03Y1370963I1221J2184D01*
G02X5000Y1371853I-456J890D01*
G01Y1373579D01*
G02X6456Y1374469I1000J0D01*
G03Y1378837I1221J2184D01*
G02X5000Y1379727I-456J890D01*
G01Y1381453D01*
G02X6456Y1382343I1000J0D01*
G03Y1386711I1221J2184D01*
G02X5000Y1387601I-456J890D01*
G01Y1469425D01*
G02X5745Y1469632I401J1D01*
G03X13221Y1469264I3861J2317D01*
G02X13865I322J-239D01*
G03Y1474634I3615J2685D01*
G02X13221I-322J239D01*
G03X5745Y1474266I-3615J-2685D01*
G02X5000Y1474473I-344J206D01*
G01Y1496787D01*
G02X5745Y1496994I401J1D01*
G03X13221Y1496626I3861J2317D01*
G02X13865I322J-239D01*
G03Y1501996I3615J2685D01*
G02X13221I-322J239D01*
G03X5745Y1501628I-3615J-2685D01*
G02X5000Y1501835I-344J206D01*
G01Y1597497D01*
X5495Y1597993D01*
X5691Y1598001D01*
G03Y1608297I-200J5148D01*
G01X5495Y1608305D01*
X5000Y1608801D01*
Y1916021D01*
G02X6731Y1916702I1000J-1D01*
G03Y1927880I6004J5589D01*
G02X5000Y1928561I-731J682D01*
G01Y2020391D01*
G02X6731Y2021072I1000J-1D01*
G03Y2032250I6004J5589D01*
G02X5000Y2032931I-731J682D01*
G01Y2064961D01*
G02X5125Y2065421I906J1D01*
G02X5264Y2065602I783J-457D01*
G02X5933Y2065867I641J-641D01*
G01X5942D01*
X5954Y2065866D01*
X19941D01*
G02X20598Y2064113I0J-1000D01*
G03X24872I2137J-2452D01*
G02X25529Y2065866I657J753D01*
G01X29941D01*
G02X30598Y2064113I0J-1000D01*
G03X34872I2137J-2452D01*
G02X35529Y2065866I657J753D01*
G01X39941D01*
G02X40598Y2064113I0J-1000D01*
G03X44872I2137J-2452D01*
G02X45529Y2065866I657J753D01*
G01X49941D01*
G02X50598Y2064113I0J-1000D01*
G03X54872I2137J-2452D01*
G02X55529Y2065866I657J753D01*
G01X92520D01*
G03X98062Y2067380I-1J10905D01*
G03X100230Y2069061I-5545J9390D01*
G03X101911Y2071230I-7710J7711D01*
G03X103424Y2076772I-9392J5542D01*
G01Y2080709D01*
G02X104288Y2081614I907J-1D01*
G01X397638D01*
G02X400512Y2078740I0J-2874D01*
G01Y7874D01*
G02X397638Y5000I-2874J0D01*
G01X104373D01*
G37*
G36*
G01X53185Y1265904D02*
G02X51478Y1266611I-707J707D01*
G01Y1281182D01*
X61046Y1290751D01*
Y1294025D01*
G02X62452Y1294939I1000J0D01*
G03X62867Y1294823I608J1373D01*
G02X63738Y1293831I-129J-992D01*
G01Y1276458D01*
X53185Y1265904D01*
G37*
G36*
G01X194449Y1378266D02*
G02X193533Y1379665I0J1000D01*
G03X193266Y1382758I-2981J1301D01*
G02X194101Y1384308I835J550D01*
G01X234568D01*
X238904Y1379973D01*
G02X238196Y1378266I-707J-707D01*
G01X194449D01*
G37*
G36*
G01X251923Y1035016D02*
X255318Y1031621D01*
G02X254611Y1029914I-707J-707D01*
G01X199443D01*
G02X198519Y1031297I0J1000D01*
G03X198523Y1033782I-3003J1247D01*
G02X199448Y1035162I925J380D01*
G01X251569D01*
G02X251923Y1035016I1J-500D01*
G37*
%LPC*%
G75*
G36*
G01X315169Y1871913D02*
G02X299003I-8083J9189D01*
G02X294834Y1881121I8084J9208D01*
G01Y1885021D01*
G02X299158Y1894363I12254J0D01*
G02X315014I7928J-9324D01*
G02X319338Y1885021I-7930J-9342D01*
G01Y1881121D01*
G02X315169Y1871913I-12253J0D01*
G37*
G36*
G01X65355Y1844272D02*
G02X44667Y1864960I0J20688D01*
G02X86043I20688J0D01*
G02X65355Y1844272I-20688J0D01*
G37*
G36*
G01X108498Y1792378D02*
G02X106044Y1792524I-1278J-789D01*
G03X106113Y1793671I-782J623D01*
G02X108567Y1793525I1278J789D01*
G03X108498Y1792378I782J-623D01*
G37*
G36*
G01X123301Y1113673D02*
G02X116539I-3381J-1508D01*
G03X115626Y1115080I-913J407D01*
G01X114413D01*
X113848Y1114515D01*
G02X111158Y1117205I-1345J1345D01*
G01X112837Y1118884D01*
X115809D01*
G03X116683Y1120369I0J1000D01*
G02X123157I3237J1796D01*
G03X124031Y1118884I874J-485D01*
G01X125247D01*
X135230Y1128866D01*
X135818D01*
G03X136690Y1130355I0J1000D01*
G02X143150I3230J1810D01*
G03X144022Y1128866I872J-489D01*
G01X149162D01*
X150954Y1127074D01*
X155722D01*
G03X156664Y1128409I0J1000D01*
G02X157111Y1130390I1792J637D01*
G01X159695Y1132973D01*
G03X159145Y1134668I-707J707D01*
G02X160620Y1135300I237J1483D01*
G01X160518Y1135151D01*
X160550Y1134792D01*
X160678Y1134664D01*
G03X161386I354J353D01*
G01X162260Y1135538D01*
X200129D01*
X235473Y1170882D01*
X307880D01*
G03X308233Y1171029I-1J500D01*
G01X311353Y1174149D01*
G02X314043Y1171459I1345J-1345D01*
G01X310387Y1167804D01*
G03Y1167096I353J-354D01*
G01X313872Y1163611D01*
G02X311182Y1160921I-1345J-1345D01*
G01X309042Y1163061D01*
G03X308689Y1163208I-354J-353D01*
G01X238860D01*
G03X238507Y1163062I0J-500D01*
G01X203006Y1127560D01*
X166717D01*
X162428Y1123272D01*
X149378D01*
X147586Y1125064D01*
X144222D01*
G03X143307Y1123660I0J-1000D01*
G02X136219Y1122085I-3387J-1495D01*
G03X134512Y1122770I-1000J-22D01*
G01X126823Y1115080D01*
X124214D01*
G03X123301Y1113673I0J-1000D01*
G37*
G36*
G01X77362Y1013681D02*
G02Y1016061I-916J1190D01*
G03X78583I611J792D01*
G02Y1013681I916J-1190D01*
G03X77362I-611J-792D01*
G37*
G36*
G01X104420Y973183D02*
G02X104281Y971032I975J-1143D01*
G03X103586Y971077I-371J-335D01*
G02X103725Y973228I-975J1143D01*
G03X104420Y973183I371J335D01*
G37*
G36*
G01X107500Y23528D02*
G02X105544Y23857I-1165J-948D01*
G03X105793Y25337I-527J850D01*
G02X107749Y25008I1165J948D01*
G03X107500Y23528I527J-850D01*
G37*
G54D19*
X59236Y670758D03*
X54483Y679810D03*
X57124Y675327D03*
X61888Y666012D03*
X63820Y579654D03*
X58750Y579653D03*
X11677Y578766D03*
X314562Y1994087D03*
X324803Y1990272D03*
X320045Y1990215D03*
X363411Y1923459D03*
X369748Y1921795D03*
X374775Y1919243D03*
X363361Y1918313D03*
X379403Y1917261D03*
X287121Y1913327D03*
X282717D03*
X278262D03*
X273817D03*
X279976Y1864565D03*
X293606Y1858668D03*
X280240D03*
X159822Y1831380D03*
X159075Y1825087D03*
X108819Y1824470D03*
X281066Y1819569D03*
X163250Y1815631D03*
X105669Y1815227D03*
X291550Y1814846D03*
X286623Y1814400D03*
X108819Y1812118D03*
X162140Y1807740D03*
X106819Y1802230D03*
X156452Y1800821D03*
X99294Y1789947D03*
X99047Y1785571D03*
X107373Y1780544D03*
X98873Y1780542D03*
X107355Y1770437D03*
X99103Y1765722D03*
X99068Y1760827D03*
X289499Y1738735D03*
X284583Y1738465D03*
X279703Y1738398D03*
X274704Y1738196D03*
X284086Y1644883D03*
X294090Y1641558D03*
X289421D03*
X348245Y1575241D03*
X355364Y1570990D03*
X348710Y1570187D03*
X361011Y1568890D03*
X367829Y1566108D03*
X54108Y1559138D03*
X11085Y1552589D03*
X16484Y1552159D03*
X302267Y1524401D03*
X313894Y1513883D03*
X301734D03*
X159526Y1483434D03*
X159216Y1477124D03*
X105455Y1472894D03*
X162242Y1471380D03*
X270234Y1467760D03*
X279990Y1464435D03*
X275521D03*
X108574Y1463389D03*
X162524Y1462651D03*
X163099Y1457084D03*
X95236Y1453321D03*
X107006Y1452651D03*
X159192Y1451105D03*
X97465Y1447919D03*
X106763Y1444599D03*
X96993Y1443743D03*
X96996Y1438980D03*
X106962Y1434041D03*
X97403Y1424340D03*
X106921Y1419492D03*
X97825D03*
X275052Y1389715D03*
X270579Y1389626D03*
X284240Y1389544D03*
X279518Y1389543D03*
X283808Y1293959D03*
X294133Y1290634D03*
X289210D03*
X293807Y1206777D03*
X289082D03*
X284194D03*
X279559D03*
X371523Y1204725D03*
X373674Y1199967D03*
X376472Y1194999D03*
X379335Y1189778D03*
X383276Y1184136D03*
X386816Y1179841D03*
X325796Y1162266D03*
X108468Y1129286D03*
X326558Y1126368D03*
X105684Y1125919D03*
X328989Y1121090D03*
X282958Y1119471D03*
X105152Y1118381D03*
X292698Y1116146D03*
X288188D03*
X164539Y1116135D03*
X331920Y1116088D03*
X337509Y1109598D03*
X162140Y1106853D03*
X344099Y1106798D03*
X108779Y1105760D03*
X349855Y1104302D03*
X156854Y1101031D03*
X98652Y1096403D03*
X107351Y1093484D03*
X96948Y1092036D03*
X96949Y1087095D03*
X107235Y1081791D03*
X96684D03*
X96774Y1072226D03*
X107215Y1072208D03*
X96904Y1067515D03*
X294617Y1031162D03*
X290107D03*
X285666D03*
X281124D03*
X175473Y1016296D03*
X175698Y1008730D03*
X184353Y1001556D03*
X100687Y999391D03*
X175449Y997660D03*
X98139Y990959D03*
X175742Y989958D03*
X184632Y983423D03*
X175022Y980281D03*
X175135Y972490D03*
X184196Y967371D03*
X175359Y963486D03*
X175561Y955964D03*
X184284Y948331D03*
X275966Y944767D03*
X175989Y944537D03*
X285874Y941442D03*
X281194D03*
X176011Y936829D03*
X343656Y933725D03*
X276686Y862488D03*
X272181Y862354D03*
X285788Y862237D03*
X281305D03*
X255837Y823626D03*
X270070Y812192D03*
X255687D03*
X159053Y787280D03*
X158956Y780982D03*
X161131Y774878D03*
X386790Y774338D03*
X273114Y770968D03*
X382892Y767710D03*
X282737Y767643D03*
X278184D03*
X391278Y765894D03*
X161644Y764231D03*
X380186Y761742D03*
X161826Y756757D03*
X376654Y754748D03*
X362577Y752783D03*
X156610Y751063D03*
X283340Y687192D03*
X278955D03*
X274514D03*
X270109D03*
X285348Y595540D03*
X333750Y595326D03*
X295509Y592215D03*
X290984D03*
X331867Y589810D03*
X337387Y586230D03*
X342900Y580126D03*
X282776Y512341D03*
X278405D03*
X273938D03*
X269516D03*
X265737Y473680D03*
X265722Y463102D03*
X274991Y463099D03*
X159019Y439268D03*
X158807Y432969D03*
X281569Y421169D03*
X161257Y420869D03*
X291002Y417844D03*
X286665D03*
X380619Y410112D03*
X161377Y407575D03*
X374442Y406857D03*
X368907Y404308D03*
X380878Y403999D03*
X363825Y401768D03*
X374542Y401282D03*
X156865Y401207D03*
X294506Y337688D03*
X289895D03*
X285513D03*
X281074D03*
X271547Y245353D03*
X281193Y241624D03*
X276617Y241400D03*
X283086Y162675D03*
X291943Y162630D03*
X296523Y162585D03*
X287420Y162540D03*
X256947Y128276D03*
X267627Y115559D03*
X257125D03*
X159417Y91281D03*
X158901Y85017D03*
X104116Y82557D03*
X387524Y76847D03*
X161742Y72497D03*
X107263Y72244D03*
X162586Y68130D03*
X294483Y67732D03*
X322005Y63778D03*
X317567D03*
X313089D03*
X308651D03*
X304151D03*
X299687D03*
X104350Y62293D03*
X379572Y58441D03*
X109054Y58250D03*
X162384Y56744D03*
X372204Y56126D03*
X365720Y52336D03*
X359931Y52189D03*
X379257Y52158D03*
X157558Y51426D03*
X107405Y49898D03*
X102646Y49461D03*
X101430Y41803D03*
X108082Y38899D03*
X97417Y37438D03*
X107037Y34687D03*
X97417Y32853D03*
G54D23*
X33263Y734923D03*
Y727049D03*
X25389Y738860D03*
X15547Y746734D03*
Y738860D03*
X25389Y730986D03*
Y723112D03*
X15547Y730986D03*
Y723112D03*
Y707364D03*
X175667Y1918217D03*
X168171D03*
X159348D03*
X151920D03*
X175667Y1910698D03*
X168171D03*
X159348D03*
X151920D03*
X175667Y1902662D03*
X168171D03*
X159348D03*
X151920D03*
X175667Y1895219D03*
X168171D03*
X159348D03*
X151920D03*
X175838Y1887301D03*
X168342D03*
X159519D03*
X152091D03*
X175838Y1880706D03*
X168342D03*
X159519D03*
X152091D03*
X175838Y1873222D03*
X168342D03*
X159519D03*
X152091D03*
X159519Y1866003D03*
X152091D03*
X248707Y1715381D03*
X241211D03*
X232388D03*
X224960D03*
X248707Y1707862D03*
X241211D03*
X232388D03*
X224960D03*
X248707Y1699826D03*
X241211D03*
X232388D03*
X224960D03*
X248707Y1692383D03*
X241211D03*
X232388D03*
X224960D03*
X248878Y1684465D03*
X241382D03*
X232559D03*
X225131D03*
X248878Y1677870D03*
X241382D03*
X232559D03*
X225131D03*
X248878Y1670386D03*
X241382D03*
X232559D03*
X225131D03*
X232559Y1663167D03*
X225131D03*
X177685Y1551435D03*
X170189D03*
X161366D03*
X153938D03*
X177685Y1543916D03*
X170189D03*
X161366D03*
X153938D03*
X177685Y1535880D03*
X170189D03*
X161366D03*
X153938D03*
X177685Y1528437D03*
X170189D03*
X161366D03*
X153938D03*
X177856Y1520519D03*
X170360D03*
X161537D03*
X154109D03*
X177856Y1513924D03*
X170360D03*
X161537D03*
X154109D03*
X177856Y1506440D03*
X170360D03*
X161537D03*
X154109D03*
X161537Y1499221D03*
X154109D03*
X25393Y1388464D03*
X15551D03*
X33267Y1384527D03*
X25393Y1380590D03*
X15551D03*
X33267Y1376653D03*
X366169Y1376210D03*
X354391D03*
X25393Y1372716D03*
X15551D03*
X33267Y1368779D03*
X366169Y1367771D03*
X354391D03*
X25393Y1364842D03*
X15551D03*
X33267Y1360905D03*
X366169Y1360043D03*
X354391D03*
X366169Y1350706D03*
X354391D03*
X366169Y1340201D03*
X354391D03*
X366169Y1329686D03*
X354391D03*
X254978Y1215296D03*
X247482D03*
X238659D03*
X231231D03*
X254978Y1207777D03*
X247482D03*
X238659D03*
X231231D03*
X254978Y1199741D03*
X247482D03*
X238659D03*
X231231D03*
X176700Y1198253D03*
X169204D03*
X160381D03*
X152953D03*
X176871Y1190335D03*
X169375D03*
X160552D03*
X153124D03*
X176871Y1183740D03*
X169375D03*
X160552D03*
X153124D03*
X176871Y1176256D03*
X169375D03*
X160552D03*
X153124D03*
X160552Y1169037D03*
X153124D03*
X15551Y1112873D03*
X33267Y1108936D03*
X25393Y1104999D03*
X15551D03*
Y1097125D03*
Y1089251D03*
X254915Y1004668D03*
X247419D03*
X238596D03*
X231168D03*
X254915Y997149D03*
X247419D03*
X238596D03*
X231168D03*
X254915Y989113D03*
X247419D03*
X238596D03*
X231168D03*
X254915Y981670D03*
X247419D03*
X238596D03*
X231168D03*
X255086Y973752D03*
X247590D03*
X238767D03*
X231339D03*
X255086Y967157D03*
X247590D03*
X238767D03*
X231339D03*
X255086Y959673D03*
X247590D03*
X238767D03*
X231339D03*
X238767Y952454D03*
X231339D03*
X179020Y867720D03*
X171524D03*
X162701D03*
X155273D03*
X179020Y860201D03*
X171524D03*
X162701D03*
X155273D03*
X179020Y852165D03*
X171524D03*
X162701D03*
X155273D03*
X179020Y844722D03*
X171524D03*
X162701D03*
X155273D03*
X179191Y836804D03*
X171695D03*
X162872D03*
X155444D03*
X179191Y830209D03*
X171695D03*
X162872D03*
X155444D03*
X179191Y822725D03*
X171695D03*
X162872D03*
X155444D03*
X254539Y639024D03*
X247043D03*
X238220D03*
X230792D03*
X254539Y631505D03*
X247043D03*
X238220D03*
X230792D03*
X279044Y624627D03*
X267433Y624321D03*
X254539Y623469D03*
X247043D03*
X238220D03*
X230792D03*
X254539Y616026D03*
X247043D03*
X238220D03*
X230792D03*
X254710Y608108D03*
X247214D03*
X238391D03*
X230963D03*
X254710Y601513D03*
X247214D03*
X238391D03*
X230963D03*
X254710Y594029D03*
X247214D03*
X238391D03*
X230963D03*
X156259Y513928D03*
X248696Y513297D03*
X241200D03*
X232377D03*
X156259Y506409D03*
X248696Y505778D03*
X241200D03*
X232377D03*
X156259Y498373D03*
X248696Y497742D03*
X241200D03*
X232377D03*
X156259Y490930D03*
X248696Y490299D03*
X241200D03*
X232377D03*
X156430Y483012D03*
X248867Y482381D03*
X241371D03*
X232548D03*
X156430Y476417D03*
X248867Y475786D03*
X241371D03*
X232548D03*
X156430Y468933D03*
X248867Y468302D03*
X241371D03*
X232548D03*
X156430Y461714D03*
X232548Y461083D03*
X174862Y313808D03*
Y306289D03*
Y298253D03*
Y290810D03*
X243862Y289990D03*
X236366D03*
X227543D03*
X175033Y282892D03*
X243862Y282471D03*
X236366D03*
X227543D03*
X175033Y276297D03*
X243862Y274435D03*
X236366D03*
X227543D03*
X175033Y268813D03*
X243862Y266992D03*
X236366D03*
X227543D03*
X175033Y261594D03*
X244033Y259074D03*
X236537D03*
X227714D03*
X244033Y252479D03*
X236537D03*
X227714D03*
X244033Y244995D03*
X236537D03*
X227714D03*
Y237776D03*
X173757Y163621D03*
X166329D03*
X173757Y156102D03*
X166329D03*
X173757Y148066D03*
X166329D03*
X173757Y140623D03*
X166329D03*
X173928Y132705D03*
X166500D03*
X173928Y126110D03*
X166500D03*
X173928Y118626D03*
X166500D03*
X173928Y111407D03*
X166500D03*
X248280Y101994D03*
X240784D03*
X248280Y94475D03*
X240784D03*
X248280Y86439D03*
X240784D03*
X248280Y78996D03*
X240784D03*
X248451Y71078D03*
X240955D03*
X248451Y64483D03*
X240955D03*
X248451Y56999D03*
X240955D03*
G54D20*
X61298Y559882D03*
X53995Y518701D03*
X51495Y559882D03*
X43995Y518701D03*
X33995D03*
X48995Y508701D03*
X38995D03*
X28995D03*
X11692Y559882D03*
X21495D03*
X23995Y518701D03*
X18995Y508701D03*
X53995Y1622992D03*
X43995D03*
X33995D03*
X23995D03*
X48995Y1612992D03*
X38995D03*
X28995D03*
X18995D03*
X61298Y1571811D03*
X51495D03*
X21495D03*
X11692D03*
G54D31*
X139920Y1948228D03*
X119920D03*
X139920Y1938228D03*
X119920D03*
X139920Y1928228D03*
X119920D03*
X139920Y1918228D03*
X119920D03*
X139920Y1908228D03*
X119920D03*
X139920Y1898228D03*
X119920D03*
X139920Y1888228D03*
X119920D03*
X139920Y1878228D03*
X119920D03*
X139920Y1868228D03*
X119920D03*
X139920Y1858228D03*
X119920D03*
X139920Y1848228D03*
X119920D03*
X139920Y1838228D03*
X119920D03*
X139920Y1828228D03*
X119920D03*
X139920Y1818228D03*
X119920D03*
X139920Y1808228D03*
X119920D03*
X139920Y1798228D03*
X119920D03*
X139920Y1788228D03*
X119920D03*
X139920Y1778228D03*
X119920D03*
X139920Y1768228D03*
X119920D03*
X139920Y1600197D03*
X119920D03*
X139920Y1590197D03*
X119920D03*
X139920Y1580197D03*
X119920D03*
X139920Y1570197D03*
X119920D03*
X139920Y1560197D03*
X119920D03*
X139920Y1550197D03*
X119920D03*
X139920Y1540197D03*
X119920D03*
X139920Y1530197D03*
X119920D03*
X139920Y1520197D03*
X119920D03*
X139920Y1510197D03*
X119920D03*
X139920Y1500197D03*
X119920D03*
X139920Y1490197D03*
X119920D03*
X139920Y1480197D03*
X119920D03*
X139920Y1470197D03*
X119920D03*
X139920Y1460197D03*
X119920D03*
X139920Y1450197D03*
X119920D03*
X139920Y1440197D03*
X119920D03*
X139920Y1430197D03*
X119920D03*
X139920Y1420197D03*
X119920D03*
X139920Y1410197D03*
X119920D03*
X139920Y1252165D03*
X119920D03*
X139920Y1242165D03*
X119920D03*
X139920Y1232165D03*
X119920D03*
X139920Y1222165D03*
X119920D03*
X139920Y1212165D03*
X119920D03*
X139920Y1202165D03*
X119920D03*
X139920Y1192165D03*
X119920D03*
X139920Y1182165D03*
X119920D03*
X139920Y1172165D03*
X119920D03*
X139920Y1162165D03*
X119920D03*
X139920Y1152165D03*
X119920D03*
X139920Y1142165D03*
X119920D03*
Y1132165D03*
X139920Y1112165D03*
Y1102165D03*
X119920D03*
X139920Y1092165D03*
X119920D03*
X139920Y1082165D03*
X119920D03*
X139920Y1072165D03*
X119920D03*
X139920Y1062165D03*
X119920D03*
X139920Y904134D03*
X119920D03*
X139920Y894134D03*
X119920D03*
X139920Y884134D03*
X119920D03*
X139920Y874134D03*
X119920D03*
X139920Y864134D03*
X119920D03*
X139920Y854134D03*
X119920D03*
X139920Y844134D03*
X119920D03*
X139920Y834134D03*
X119920D03*
X139920Y824134D03*
X119920D03*
X139920Y814134D03*
X119920D03*
X139920Y804134D03*
X119920D03*
X139920Y794134D03*
X119920D03*
X139920Y784134D03*
X119920D03*
X139920Y774134D03*
X119920D03*
X139920Y764134D03*
X119920D03*
X139920Y754134D03*
X119920D03*
X139920Y744134D03*
X119920D03*
X139920Y734134D03*
X119920D03*
X139920Y724134D03*
X119920D03*
X139920Y714134D03*
Y556102D03*
Y546102D03*
Y536102D03*
Y526102D03*
Y516102D03*
Y506102D03*
Y496102D03*
Y486102D03*
Y476102D03*
Y466102D03*
Y456102D03*
Y446102D03*
Y436102D03*
Y426102D03*
Y416102D03*
Y406102D03*
Y396102D03*
Y386102D03*
Y376102D03*
Y366102D03*
Y208071D03*
X119920D03*
X139920Y198071D03*
X119920D03*
X139920Y188071D03*
X119920D03*
X139920Y178071D03*
X119920D03*
X139920Y168071D03*
X119920D03*
X139920Y158071D03*
X119920D03*
X139920Y148071D03*
X119920D03*
X139920Y138071D03*
X119920D03*
X139920Y128071D03*
X119920D03*
X139920Y118071D03*
X119920D03*
X139920Y108071D03*
X119920D03*
X139920Y98071D03*
X119920D03*
X139920Y88071D03*
Y78071D03*
Y68071D03*
X119920Y58071D03*
X139920Y48071D03*
X119920D03*
X139920Y38071D03*
X119920D03*
X139920Y28071D03*
X119920D03*
X139920Y18071D03*
X119920D03*
G54D29*
X243385Y1957520D03*
X233385D03*
X223385D03*
X213385D03*
X203385D03*
X193385D03*
X183385D03*
X173385D03*
X243385Y1946890D03*
X233385D03*
X223385D03*
X213385D03*
X203385D03*
X193385D03*
X183385D03*
X173385D03*
X243385Y1782520D03*
X233385D03*
X223385D03*
X213385D03*
X203385D03*
X193385D03*
X183385D03*
X173385D03*
X243385Y1771890D03*
X233385D03*
X223385D03*
X213385D03*
X203385D03*
X193385D03*
X183385D03*
X173385D03*
X243385Y1607520D03*
X233385D03*
X223385D03*
X213385D03*
X203385D03*
X193385D03*
X183385D03*
X173385D03*
X243385Y1596890D03*
X233385D03*
X223385D03*
X213385D03*
X203385D03*
X193385D03*
X183385D03*
X173385D03*
X243385Y1432520D03*
X233385D03*
X223385D03*
X213385D03*
X203385D03*
X193385D03*
X183385D03*
X173385D03*
X243385Y1421890D03*
X233385D03*
X223385D03*
X213385D03*
X203385D03*
X193385D03*
X183385D03*
X173385D03*
X243385Y1257520D03*
X233385D03*
X223385D03*
X213385D03*
X203385D03*
X193385D03*
X183385D03*
X173385D03*
X362165Y1254705D03*
X357165Y1249705D03*
X337165D03*
X243385Y1246890D03*
X233385D03*
X223385D03*
X213385D03*
X203385D03*
X193385D03*
X183385D03*
X173385D03*
X362165Y1244705D03*
X243385Y1082520D03*
X233385D03*
X223385D03*
X213385D03*
X203385D03*
X193385D03*
X183385D03*
X173385D03*
X243385Y1071890D03*
X233385D03*
X223385D03*
X213385D03*
X203385D03*
X193385D03*
X183385D03*
X173385D03*
X243385Y907520D03*
X233385D03*
X223385D03*
X213385D03*
X203385D03*
X193385D03*
X183385D03*
X173385D03*
X362165Y904705D03*
X243385Y896890D03*
X233385D03*
X223385D03*
X213385D03*
X203385D03*
X193385D03*
X183385D03*
X173385D03*
X362165Y894705D03*
X342165D03*
X243386Y732520D03*
X233386D03*
X223386D03*
X213386D03*
X203386D03*
X193386D03*
X183386D03*
X173386D03*
X243386Y721890D03*
X233386D03*
X223386D03*
X213386D03*
X203386D03*
X193386D03*
X183386D03*
X173386D03*
X357166Y559705D03*
X243386Y557520D03*
X233386D03*
X223386D03*
X213386D03*
X203386D03*
X193386D03*
X183386D03*
X173386D03*
X362166Y554705D03*
X243386Y546890D03*
X233386D03*
X223386D03*
X213386D03*
X203386D03*
X193386D03*
X183386D03*
X173386D03*
X362166Y544705D03*
X243385Y382520D03*
X233385D03*
X223385D03*
X213385D03*
X203385D03*
X193385D03*
X183385D03*
X173385D03*
X243385Y371890D03*
X233385D03*
X223385D03*
X213385D03*
X203385D03*
X193385D03*
X183385D03*
X173385D03*
X243385Y207520D03*
X233385D03*
X223385D03*
X213385D03*
X203385D03*
X193385D03*
X183385D03*
X173385D03*
X362165Y204705D03*
X357165Y199705D03*
X243385Y196890D03*
X233385D03*
X223385D03*
X213385D03*
X203385D03*
X193385D03*
X183385D03*
X173385D03*
X362165Y194705D03*
X243385Y32520D03*
X233385D03*
X223385D03*
X213385D03*
X203385D03*
X193385D03*
X183385D03*
X173385D03*
X243385Y21890D03*
X233385D03*
X223385D03*
X213385D03*
X203385D03*
X193385D03*
X183385D03*
X173385D03*
G54D22*
X52735Y216976D03*
X32735Y425834D03*
X42735D03*
X37735Y415834D03*
X47735D03*
X42735Y243811D03*
X32735D03*
X47735Y233811D03*
X37735D03*
Y206976D03*
X47735D03*
X32735Y216976D03*
X42735D03*
X22735Y425834D03*
X17735Y415834D03*
X27735D03*
X22735Y243811D03*
X27735Y233811D03*
X17735D03*
Y206976D03*
X27735D03*
X22735Y216976D03*
X47735Y2051661D03*
X37735D03*
X27735D03*
X17735D03*
X191530Y2043388D03*
X192125Y1998730D03*
X52735Y1957291D03*
X42735D03*
X32735D03*
X22735D03*
X47735Y1947291D03*
X37735D03*
X27735D03*
X17735D03*
X190289Y1900420D03*
X191530Y1823227D03*
X191607Y1731351D03*
X192143Y1648177D03*
X191079Y1557277D03*
X189463Y1474162D03*
X191846Y1299104D03*
X191342Y1206233D03*
X191250Y1122856D03*
X196311Y947202D03*
X191606Y856244D03*
X191846Y774526D03*
X190816Y681645D03*
X192888Y598130D03*
X190553Y506517D03*
X189761Y421732D03*
X190817Y331786D03*
X190357Y247568D03*
X190289Y152050D03*
X189762Y73105D03*
G54D32*
X45056Y1817693D03*
X23402D03*
Y1801158D03*
Y1784622D03*
X45056Y1768087D03*
X23402D03*
Y1751551D03*
Y1735016D03*
Y1718480D03*
Y1701945D03*
Y1685410D03*
X45056Y1668874D03*
X23402D03*
G54D21*
X67499Y528544D03*
Y1603149D03*
G54D24*
X20468Y696341D03*
G54D34*
X307086Y308267D03*
G54D26*
X307087Y2043503D03*
Y1693503D03*
Y827164D03*
Y477164D03*
Y127164D03*
G54D30*
X163385Y1952205D03*
Y1602205D03*
Y1252205D03*
Y1077205D03*
Y902205D03*
X163386Y727205D03*
Y552205D03*
X163385Y377205D03*
Y202205D03*
Y27205D03*
G54D27*
X57735Y2026661D03*
Y1922291D03*
Y59953D03*
G54D33*
X373385Y1782520D03*
Y1607520D03*
Y1432520D03*
Y1257520D03*
Y1082520D03*
Y907520D03*
X373386Y732520D03*
Y557520D03*
X373385Y382520D03*
Y207520D03*
Y32520D03*
G54D28*
X359842Y2003780D03*
Y1828779D03*
Y1653780D03*
Y1478780D03*
Y1303780D03*
Y1128779D03*
Y953780D03*
Y778780D03*
Y603779D03*
Y428779D03*
Y253780D03*
Y78780D03*
G54D25*
X58995Y543701D03*
X13995D03*
X58995Y1587992D03*
X13995D03*
%LPD*%
G75*
G54D10*
X17735Y24953D03*
X27735D03*
X22735Y34953D03*
X47735Y24953D03*
X42735Y34953D03*
X52735D03*
X203542Y73105D03*
X204069Y152050D03*
X204137Y247568D03*
X204597Y331786D03*
X203541Y421732D03*
X204333Y506517D03*
X206668Y598130D03*
X204596Y681645D03*
X205626Y774526D03*
X205386Y856244D03*
X210091Y947202D03*
X209296Y1032544D03*
X205030Y1122856D03*
X205122Y1206233D03*
X205626Y1299104D03*
X204332Y1380966D03*
X203243Y1474162D03*
X204859Y1557277D03*
X205923Y1648177D03*
X205387Y1731351D03*
X205310Y1823227D03*
X204069Y1900420D03*
X205905Y1998730D03*
X205310Y2043388D03*
G54D11*
X25219Y18752D03*
X3001Y52034D03*
Y100034D03*
Y150034D03*
Y200034D03*
Y250034D03*
Y300034D03*
Y350034D03*
Y400034D03*
Y450034D03*
Y500034D03*
Y550034D03*
Y600034D03*
Y650034D03*
Y700034D03*
Y750034D03*
Y800034D03*
Y850034D03*
Y900034D03*
Y950034D03*
Y1000034D03*
Y1050034D03*
Y1100034D03*
Y1150034D03*
Y1200034D03*
Y1250034D03*
Y1300034D03*
Y1350034D03*
Y1400034D03*
Y1450034D03*
Y1500034D03*
Y1550034D03*
X3006Y1594602D03*
X3012Y1610165D03*
X3001Y1650034D03*
Y1700034D03*
Y1750034D03*
Y1800034D03*
Y1850034D03*
Y1900034D03*
Y1950034D03*
Y2000034D03*
Y2050034D03*
X49441Y1238962D03*
X46980Y1325843D03*
Y1315843D03*
Y1320843D03*
Y1330843D03*
Y1345843D03*
Y1340843D03*
X26833Y2067866D03*
X70865Y897750D03*
X58356Y1279812D03*
X58416Y1272383D03*
X75219Y18752D03*
X93223Y417736D03*
X94347Y421562D03*
X82763Y1060051D03*
X76833Y2067866D03*
X114498Y396207D03*
X112503Y1115860D03*
X100719Y1312810D03*
Y1346065D03*
X109991Y2083607D03*
X125219Y3002D03*
X144878Y1738861D03*
X161339Y88108D03*
X161517Y436119D03*
X161479Y784141D03*
X158456Y1129045D03*
X158618Y1399448D03*
X164037Y1400226D03*
X170351Y1401324D03*
X150309Y1737009D03*
X168151Y1739208D03*
X156183Y1735240D03*
X165782Y1732903D03*
X163257Y1737619D03*
X161844Y1828225D03*
X159991Y2083607D03*
X175219Y3002D03*
X176083Y1402321D03*
X173394Y1736051D03*
X209991Y2083607D03*
X225219Y3002D03*
X259991Y2083607D03*
X275219Y3002D03*
X308057Y248863D03*
X306267Y241010D03*
X314940Y252083D03*
X305867Y258589D03*
X309678Y1053262D03*
X312527Y1162266D03*
X312698Y1172804D03*
X312077Y1575871D03*
X292614Y1864565D03*
X309991Y2083607D03*
X325219Y3002D03*
X331403Y51409D03*
X333889Y56021D03*
X338227Y61559D03*
X329930Y245684D03*
X320961Y250105D03*
X335522Y404033D03*
X323313Y418313D03*
X326196Y413982D03*
X328950Y409216D03*
X320980Y423225D03*
X319305Y582111D03*
X317724Y588250D03*
X320380Y576491D03*
X323751Y589155D03*
X319852Y593330D03*
X321742Y599041D03*
X331568Y752967D03*
X339012Y752859D03*
X329336Y762693D03*
X334010Y758588D03*
X327524Y758020D03*
X339615Y926357D03*
X324098Y946104D03*
X326646Y939788D03*
X333300Y928464D03*
X328583Y933262D03*
X321425Y951577D03*
X324246Y1051786D03*
X335677Y1048904D03*
X317592Y1053050D03*
X323403Y1172804D03*
X327452Y1279447D03*
X321978Y1282086D03*
X338047Y1282599D03*
X333242Y1276809D03*
X329619Y1284016D03*
X327932Y1289221D03*
X334646Y1400804D03*
X323720Y1570924D03*
X329399Y1571939D03*
X317243Y1574832D03*
X333474Y1566686D03*
X335963Y1573797D03*
X338309Y1927623D03*
X332399Y1926787D03*
X348289Y50863D03*
X345089Y56190D03*
X340373Y51579D03*
X342097Y401684D03*
X344109Y751809D03*
X345578Y1047844D03*
X344130Y1401670D03*
X345537Y1916558D03*
X344402Y1911123D03*
X340336Y1922409D03*
X347676Y1922165D03*
X359991Y2083607D03*
X375219Y3002D03*
X402512Y17108D03*
Y67108D03*
Y117108D03*
Y167108D03*
Y217108D03*
Y267108D03*
Y317108D03*
Y367108D03*
Y417108D03*
Y467108D03*
Y517108D03*
Y567108D03*
Y617108D03*
Y667108D03*
Y717108D03*
Y767108D03*
Y817108D03*
Y867108D03*
Y917108D03*
Y967108D03*
Y1017108D03*
Y1067108D03*
Y1117108D03*
Y1167108D03*
Y1217108D03*
Y1267108D03*
Y1317108D03*
Y1367108D03*
Y1417108D03*
Y1467108D03*
Y1517108D03*
Y1567108D03*
Y1617108D03*
Y1667108D03*
Y1717108D03*
Y1767108D03*
Y1817108D03*
Y1867108D03*
Y1917108D03*
Y1967108D03*
Y2017108D03*
Y2067108D03*
G54D12*
X25389Y707364D03*
X7673Y703427D03*
X15547Y715238D03*
X25389D03*
X7673Y711301D03*
X15547Y770357D03*
Y778231D03*
X7673Y774293D03*
Y782167D03*
X15547Y786105D03*
X7673Y790041D03*
X15547Y849097D03*
X25389D03*
X7673Y845160D03*
X25389Y864845D03*
X15547Y896341D03*
X25389Y880593D03*
Y888467D03*
X7673Y900278D03*
X15547Y912089D03*
Y919963D03*
X25389D03*
X7673Y908152D03*
Y916026D03*
X25389Y927837D03*
Y935711D03*
X15547Y959333D03*
Y967207D03*
Y975081D03*
X25389D03*
X7673Y955396D03*
Y971144D03*
Y979018D03*
X25389Y990829D03*
Y998703D03*
X15551Y1065629D03*
X7677Y1061692D03*
X15551Y1073503D03*
Y1081377D03*
X25393D03*
Y1089251D03*
X7677Y1077440D03*
Y1085314D03*
X15551Y1120748D03*
X25393Y1097125D03*
X15551Y1136496D03*
Y1144370D03*
X25393Y1136496D03*
Y1144370D03*
X7677Y1124684D03*
Y1132558D03*
Y1140432D03*
X25393Y1160118D03*
X15551Y1183740D03*
Y1191614D03*
X7677Y1179803D03*
X15551Y1199488D03*
X25393D03*
Y1207362D03*
Y1215236D03*
X7677Y1195551D03*
Y1203425D03*
X15551Y1238858D03*
X25393Y1223110D03*
X15551Y1254606D03*
Y1262480D03*
X7677Y1242795D03*
Y1250669D03*
Y1258543D03*
X15551Y1270354D03*
Y1333346D03*
X25393Y1325472D03*
X7677Y1321535D03*
Y1353031D03*
X15551Y1349094D03*
X33263Y703427D03*
Y711301D03*
Y719175D03*
Y845160D03*
Y868782D03*
Y876656D03*
Y884530D03*
Y916026D03*
Y923900D03*
Y939648D03*
Y979018D03*
Y994766D03*
Y1002640D03*
X33267Y1077440D03*
Y1085314D03*
Y1101062D03*
Y1140432D03*
Y1148306D03*
Y1156180D03*
Y1195551D03*
Y1203425D03*
Y1219173D03*
Y1227047D03*
Y1337283D03*
X165975Y265783D03*
Y296140D03*
Y286803D03*
Y276298D03*
Y312307D03*
Y303868D03*
X157272Y604773D03*
Y633416D03*
Y613574D03*
Y624079D03*
Y641144D03*
Y649583D03*
X166699Y972924D03*
Y983439D03*
Y993944D03*
X166424Y1011298D03*
Y1003570D03*
Y1019737D03*
X155749Y1307733D03*
Y1328753D03*
Y1318248D03*
Y1354257D03*
Y1338090D03*
Y1345818D03*
X158492Y1667763D03*
Y1657248D03*
Y1695333D03*
Y1687605D03*
Y1678268D03*
Y1703772D03*
X219214Y1287272D03*
Y1301975D03*
X219349Y1308924D03*
X219214Y1294491D03*
X219178Y1324285D03*
Y1332321D03*
Y1316842D03*
Y1339840D03*
X243741Y153964D03*
X222732D03*
X232700D03*
X243741Y170131D03*
Y161692D03*
X222732Y170131D03*
Y161692D03*
X232700Y170131D03*
Y161692D03*
X239746Y407393D03*
Y396878D03*
Y417898D03*
X243980Y754782D03*
X234012D03*
X243980Y762510D03*
Y770949D03*
X234012Y762510D03*
Y770949D03*
X226642Y1287272D03*
Y1301975D03*
X235465D03*
X226777Y1308924D03*
X235600D03*
X242961Y1301975D03*
X243096Y1308924D03*
X226642Y1294491D03*
X235465D03*
X242961D03*
X226606Y1324285D03*
X235429D03*
X226606Y1332321D03*
X235429D03*
X242925Y1324285D03*
Y1332321D03*
X226606Y1316842D03*
X235429D03*
X242925D03*
X226606Y1339840D03*
X235429D03*
X242925D03*
X224573Y2031480D03*
X234541D03*
X224573Y2020965D03*
X234541D03*
X224573Y2059050D03*
X234541Y2051322D03*
Y2059050D03*
X224573Y2041985D03*
Y2051322D03*
X234541Y2041985D03*
Y2067489D03*
X224573D03*
X256566Y54944D03*
X264104D03*
X256566Y45572D03*
X264104D03*
X256566Y65449D03*
X264104D03*
X264861Y153964D03*
X253083D03*
X264861Y170131D03*
Y161692D03*
X253083Y170131D03*
Y161692D03*
X264596Y221664D03*
X252818D03*
X264596Y242684D03*
Y232179D03*
X252818Y242684D03*
Y232179D03*
X264596Y268188D03*
Y259749D03*
Y252021D03*
X252818Y268188D03*
Y252021D03*
Y259749D03*
X266040Y407146D03*
Y396631D03*
Y417651D03*
X257572Y396630D03*
Y407145D03*
X248714Y407536D03*
Y397021D03*
X257572Y417650D03*
X248714Y418041D03*
X267166Y581440D03*
Y572639D03*
Y609010D03*
Y601282D03*
Y591945D03*
Y617449D03*
X255021Y754782D03*
Y762510D03*
Y770949D03*
X263174Y855159D03*
Y862887D03*
X251396D03*
Y855159D03*
Y871326D03*
X263174D03*
X262766Y949344D03*
Y967106D03*
Y959859D03*
X262621Y974386D03*
Y990553D03*
Y982114D03*
X261219Y1124364D03*
Y1134879D03*
X251251Y1124364D03*
Y1134879D03*
X261219Y1145384D03*
X251251D03*
X259581Y1272430D03*
Y1282945D03*
Y1293450D03*
Y1302787D03*
Y1310515D03*
Y1318954D03*
X263939Y1548010D03*
Y1534139D03*
Y1541055D03*
X261564Y1621823D03*
Y1642843D03*
Y1632338D03*
Y1668347D03*
Y1659908D03*
Y1652180D03*
X265759Y1697613D03*
X254718D03*
X265759Y1676593D03*
Y1687108D03*
X254718D03*
Y1676593D03*
X254457Y1722140D03*
X265498D03*
X265759Y1714678D03*
X254718D03*
Y1706950D03*
X265759D03*
X258639Y1819074D03*
Y1812119D03*
Y1805203D03*
X250468Y1819074D03*
Y1812119D03*
Y1805203D03*
X267396Y1819077D03*
Y1805206D03*
Y1812122D03*
X258459Y1826219D03*
X250288D03*
X267037Y1826222D03*
X258459Y1840090D03*
Y1833135D03*
X267037Y1833138D03*
Y1840093D03*
X250288Y1833135D03*
Y1840090D03*
X245582Y2031480D03*
Y2020965D03*
X258337D03*
Y2031480D03*
X245582Y2041985D03*
Y2051322D03*
Y2059050D03*
X258337Y2051322D03*
Y2059050D03*
Y2041985D03*
Y2067489D03*
X245582D03*
X288102Y54944D03*
Y45572D03*
X271572Y54944D03*
X279754D03*
X271572Y45572D03*
X279754D03*
X288102Y65449D03*
X271572D03*
X279754D03*
X274531Y407289D03*
Y396774D03*
Y417794D03*
X278944Y581440D03*
Y572639D03*
Y601282D03*
Y609010D03*
Y591945D03*
Y617449D03*
X274544Y949344D03*
Y967106D03*
Y959859D03*
X274399Y974386D03*
Y990553D03*
Y982114D03*
X279015Y1124077D03*
X288363Y1123935D03*
X279015Y1134592D03*
X288363Y1134450D03*
X269975Y1134735D03*
Y1124220D03*
X288363Y1144955D03*
X279015Y1145097D03*
X269975Y1145240D03*
X286721Y1184312D03*
Y1192040D03*
X278182Y1184455D03*
Y1192183D03*
X286721Y1200479D03*
X278182Y1200622D03*
X270622Y1282945D03*
Y1272430D03*
Y1293450D03*
Y1302787D03*
Y1310515D03*
Y1318954D03*
X278400Y1548190D03*
X271534Y1548010D03*
X285995Y1548190D03*
X278400Y1534319D03*
Y1541235D03*
X271534Y1534139D03*
Y1541055D03*
X285995Y1534319D03*
Y1541235D03*
X273342Y1621823D03*
Y1642843D03*
Y1632338D03*
Y1668347D03*
Y1652180D03*
Y1659908D03*
X270115Y2031480D03*
Y2020965D03*
Y2051322D03*
Y2059050D03*
Y2041985D03*
Y2067489D03*
X300537Y516309D03*
X307966Y516419D03*
Y524147D03*
X300537Y524037D03*
Y532476D03*
X307966Y532586D03*
X292569Y524323D03*
Y516595D03*
Y532762D03*
X315187Y652457D03*
Y661258D03*
X304146D03*
Y652457D03*
Y681100D03*
X315187D03*
Y671763D03*
X304146D03*
X315187Y688828D03*
X304146D03*
Y697267D03*
X315187D03*
X307194Y1020657D03*
X307078Y1007303D03*
X307274Y1001286D03*
X307143Y1014094D03*
X307129Y1027081D03*
X306999Y1033718D03*
X303159Y1184526D03*
Y1192254D03*
X311936Y1192253D03*
Y1184525D03*
X294691Y1184526D03*
Y1192254D03*
X311936Y1200692D03*
X303159Y1200693D03*
X294691D03*
X309823Y1472957D03*
X309464Y1480102D03*
X309823Y1466002D03*
Y1459086D03*
X292715Y1480099D03*
X292895Y1472954D03*
X301066D03*
X300886Y1480099D03*
X292895Y1459083D03*
Y1465999D03*
X301066D03*
Y1459083D03*
X309464Y1493973D03*
Y1487018D03*
X292715Y1487015D03*
Y1493970D03*
X300886D03*
Y1487015D03*
X292754Y1917148D03*
X300349D03*
X292754Y1910232D03*
X300349D03*
X307215Y1910412D03*
X314810D03*
Y1917328D03*
X307215D03*
X292754Y1924103D03*
X300349D03*
X314810Y1924283D03*
X307215D03*
X332775Y318634D03*
X332693Y311980D03*
X332775Y335272D03*
Y342461D03*
Y325935D03*
X332685Y348655D03*
X325139Y516632D03*
Y524360D03*
X316791Y524432D03*
Y516704D03*
Y532871D03*
X325139Y532799D03*
X318235Y1020657D03*
X318315Y1001286D03*
X318119Y1007303D03*
X318184Y1014094D03*
X318170Y1027081D03*
X318040Y1033718D03*
X343816Y318634D03*
X343734Y311980D03*
X343816Y335272D03*
Y342461D03*
Y325935D03*
X343726Y348655D03*
G54D13*
X45056Y1685410D03*
Y1701945D03*
Y1718480D03*
Y1735016D03*
Y1751551D03*
Y1784622D03*
Y1801158D03*
G54D14*
X119920Y68071D03*
Y218071D03*
Y228071D03*
Y238071D03*
Y248071D03*
Y258071D03*
Y268071D03*
Y278071D03*
Y288071D03*
Y298071D03*
Y308071D03*
Y318071D03*
Y328071D03*
Y566102D03*
Y576102D03*
Y586102D03*
Y596102D03*
Y606102D03*
Y616102D03*
Y626102D03*
Y636102D03*
Y646102D03*
Y656102D03*
Y666102D03*
Y676102D03*
Y914134D03*
Y924134D03*
Y934134D03*
Y944134D03*
Y954134D03*
Y964134D03*
Y974134D03*
Y984134D03*
Y994134D03*
Y1004134D03*
Y1014134D03*
Y1024134D03*
Y1262165D03*
Y1272165D03*
Y1282165D03*
Y1292165D03*
Y1302165D03*
Y1312165D03*
Y1322165D03*
Y1332165D03*
Y1342165D03*
Y1352165D03*
Y1362165D03*
Y1372165D03*
Y1610197D03*
Y1620197D03*
Y1630197D03*
Y1640197D03*
Y1650197D03*
Y1660197D03*
Y1670197D03*
Y1680197D03*
Y1690197D03*
Y1700197D03*
Y1710197D03*
Y1720197D03*
Y1958228D03*
Y1968228D03*
Y1978228D03*
Y1988228D03*
Y1998228D03*
Y2008228D03*
Y2018228D03*
Y2028228D03*
Y2038228D03*
Y2048228D03*
Y2058228D03*
Y2068228D03*
X139920Y58071D03*
Y228071D03*
Y218071D03*
Y248071D03*
Y238071D03*
Y268071D03*
Y258071D03*
Y298071D03*
Y288071D03*
Y278071D03*
Y318071D03*
Y308071D03*
Y328071D03*
Y566102D03*
Y586102D03*
Y576102D03*
Y606102D03*
Y596102D03*
Y636102D03*
Y626102D03*
Y616102D03*
Y656102D03*
Y646102D03*
Y676102D03*
Y666102D03*
Y924134D03*
Y914134D03*
Y944134D03*
Y934134D03*
Y974134D03*
Y964134D03*
Y954134D03*
Y994134D03*
Y984134D03*
Y1024134D03*
Y1014134D03*
Y1004134D03*
Y1262165D03*
Y1282165D03*
Y1272165D03*
Y1312165D03*
Y1302165D03*
Y1292165D03*
Y1332165D03*
Y1322165D03*
Y1362165D03*
Y1352165D03*
Y1342165D03*
Y1372165D03*
Y1620197D03*
Y1610197D03*
Y1650197D03*
Y1640197D03*
Y1630197D03*
Y1670197D03*
Y1660197D03*
Y1700197D03*
Y1690197D03*
Y1680197D03*
Y1720197D03*
Y1710197D03*
Y1958228D03*
Y1988228D03*
Y1978228D03*
Y1968228D03*
Y2008228D03*
Y1998228D03*
Y2038228D03*
Y2028228D03*
Y2018228D03*
Y2058228D03*
Y2048228D03*
Y2068228D03*
G54D15*
X253385Y21890D03*
Y32520D03*
X263385Y21890D03*
Y32520D03*
X253385Y196890D03*
X263385D03*
X253385Y207520D03*
X263385D03*
X253385Y371890D03*
X263385D03*
X253385Y382520D03*
X263385D03*
X253386Y546890D03*
Y557520D03*
X263386Y546890D03*
Y557520D03*
X253386Y721890D03*
Y732520D03*
X263386Y721890D03*
Y732520D03*
X253385Y896890D03*
X263385D03*
X253385Y907520D03*
X263385D03*
X253385Y1071890D03*
X263385D03*
X253385Y1082520D03*
X263385D03*
X253385Y1246890D03*
Y1257520D03*
X263385Y1246890D03*
Y1257520D03*
X253385Y1421890D03*
Y1432520D03*
X263385Y1421890D03*
Y1432520D03*
X253385Y1596890D03*
X263385D03*
X253385Y1607520D03*
X263385D03*
X253385Y1771890D03*
X263385D03*
X253385Y1782520D03*
X263385D03*
X253385Y1946890D03*
Y1957520D03*
X263385Y1946890D03*
Y1957520D03*
X273385Y21890D03*
Y32520D03*
X283385Y21890D03*
Y32520D03*
X273385Y196890D03*
X283385D03*
X273385Y207520D03*
X283385D03*
X273385Y371890D03*
X283385D03*
X273385Y382520D03*
X283385D03*
X273386Y546890D03*
Y557520D03*
X283386Y546890D03*
Y557520D03*
X273386Y721890D03*
Y732520D03*
X283386Y721890D03*
Y732520D03*
X273385Y896890D03*
X283385D03*
X273385Y907520D03*
X283385D03*
X273385Y1071890D03*
X283385D03*
X273385Y1082520D03*
X283385D03*
X273385Y1246890D03*
Y1257520D03*
X283385Y1246890D03*
Y1257520D03*
X273385Y1421890D03*
Y1432520D03*
X283385Y1421890D03*
Y1432520D03*
X273385Y1596890D03*
X283385D03*
X273385Y1607520D03*
X283385D03*
X273385Y1771890D03*
X283385D03*
X273385Y1782520D03*
X283385D03*
X273385Y1946890D03*
Y1957520D03*
X283385Y1946890D03*
Y1957520D03*
X293385Y21890D03*
Y32520D03*
X303385Y21890D03*
Y32520D03*
X313385D03*
Y21890D03*
X293385Y196890D03*
X303385D03*
X313385D03*
X293385Y207520D03*
X303385D03*
X313385D03*
X293385Y371890D03*
X303385D03*
X313385D03*
X293385Y382520D03*
X303385D03*
X313385D03*
X293386Y546890D03*
Y557520D03*
X303386Y546890D03*
Y557520D03*
X313386D03*
Y546890D03*
X293386Y721890D03*
Y732520D03*
X303386Y721890D03*
Y732520D03*
X313386D03*
Y721890D03*
X293385Y896890D03*
X303385D03*
X313385D03*
X293385Y907520D03*
X303385D03*
X313385D03*
X293385Y1071890D03*
X303385D03*
X313385D03*
X293385Y1082520D03*
X303385D03*
X313385D03*
X293385Y1246890D03*
Y1257520D03*
X303385Y1246890D03*
Y1257520D03*
X313385D03*
Y1246890D03*
X293385Y1421890D03*
Y1432520D03*
X303385Y1421890D03*
Y1432520D03*
X313385D03*
Y1421890D03*
X293385Y1596890D03*
X303385D03*
X313385D03*
X293385Y1607520D03*
X303385D03*
X313385D03*
X293385Y1771890D03*
X303385D03*
X313385D03*
X293385Y1782520D03*
X303385D03*
X313385D03*
X293385Y1946890D03*
Y1957520D03*
X303385Y1946890D03*
Y1957520D03*
X313385D03*
Y1946890D03*
X337165Y24705D03*
X323385Y32520D03*
Y21890D03*
Y196890D03*
X337165Y209705D03*
X323385Y207520D03*
Y371890D03*
X337165Y374705D03*
X323385Y382520D03*
X337166Y559705D03*
X323386Y557520D03*
Y546890D03*
X337166Y724705D03*
X323386Y732520D03*
Y721890D03*
X323385Y896890D03*
X337165Y909705D03*
X323385Y907520D03*
Y1071890D03*
X337165Y1074705D03*
X323385Y1082520D03*
X337165Y1259705D03*
X323385Y1257520D03*
Y1246890D03*
X337165Y1424705D03*
X323385Y1432520D03*
Y1421890D03*
Y1596890D03*
X337165Y1609705D03*
X323385Y1607520D03*
Y1771890D03*
X337165Y1774705D03*
Y1784705D03*
X323385Y1782520D03*
X337165Y1959705D03*
X323385Y1957520D03*
Y1946890D03*
X342165Y19705D03*
X357165Y24705D03*
X362165Y19705D03*
Y29705D03*
X357165Y34705D03*
X347165Y199705D03*
X352165Y194705D03*
X342165Y204705D03*
X347165Y209705D03*
X352165Y204705D03*
X342165Y369705D03*
X362165D03*
X357165Y374705D03*
Y384705D03*
X362165Y379705D03*
X342166Y554705D03*
X347166Y549705D03*
Y559705D03*
X352166Y544705D03*
Y554705D03*
X342166Y719705D03*
X357166Y724705D03*
X362166Y719705D03*
Y729705D03*
X357166Y734705D03*
X347165Y899705D03*
X352165Y894705D03*
X342165Y904705D03*
X347165Y909705D03*
X352165Y904705D03*
X342165Y1069705D03*
X362165D03*
X357165Y1074705D03*
Y1084705D03*
X362165Y1079705D03*
X342165Y1254705D03*
X347165Y1249705D03*
Y1259705D03*
X352165Y1244705D03*
Y1254705D03*
X342165Y1419705D03*
X357165Y1424705D03*
Y1434705D03*
X362165Y1419705D03*
Y1429705D03*
X347165Y1599705D03*
X352165Y1594705D03*
X342165Y1604705D03*
X347165Y1609705D03*
X352165Y1604705D03*
X342165Y1769705D03*
X362165D03*
X342165Y1779705D03*
X357165Y1774705D03*
Y1784705D03*
X362165Y1779705D03*
X342165Y1954705D03*
X347165Y1949705D03*
Y1959705D03*
X352165Y1944705D03*
Y1954705D03*
G54D16*
G01X112503Y1115860D02*
X113625Y1116982D01*
X126035D01*
X136018Y1126965D01*
X148374D01*
X150166Y1125173D01*
X161640D01*
X165929Y1129462D01*
X202218D01*
X237865Y1165109D01*
X309684D01*
X312527Y1162266D01*
G01X158456Y1129045D02*
X163048Y1133637D01*
X200917D01*
X236261Y1168981D01*
X308875D01*
X312698Y1172804D01*
G54D17*
G01X15547Y770357D02*
X11972Y766782D01*
Y761408D01*
X13936Y759444D01*
X17756D01*
X21043Y756157D01*
Y754209D01*
X23909Y751343D01*
X27883D01*
X31475Y747751D01*
X35619D01*
X39678Y743692D01*
Y701885D01*
X77271Y664292D01*
Y519469D01*
X37410Y479608D01*
Y452096D01*
X57755Y431751D01*
Y412866D01*
X43723Y398834D01*
Y261583D01*
X67713Y237593D01*
Y160250D01*
X38434Y130971D01*
Y47028D01*
X27394Y35988D01*
Y32336D01*
X24400Y29342D01*
X22124D01*
X17735Y24953D01*
G01X7673Y774293D02*
X10672Y771294D01*
Y760493D01*
X10736Y760429D01*
Y760428D01*
X13286Y757877D01*
X17106D01*
X19476Y755507D01*
Y753559D01*
X23259Y749776D01*
X27233D01*
X30825Y746184D01*
X35296D01*
X38281Y743199D01*
Y701443D01*
X75971Y663753D01*
Y520008D01*
X36110Y480147D01*
Y451557D01*
X56455Y431212D01*
Y413405D01*
X42423Y399373D01*
Y261044D01*
X66413Y237054D01*
Y160790D01*
X37134Y131511D01*
Y49352D01*
X22735Y34953D01*
G01X27735Y24953D02*
X39734Y36952D01*
Y130432D01*
X69013Y159711D01*
Y238132D01*
X45023Y262122D01*
Y398295D01*
X59055Y412327D01*
Y432290D01*
X38710Y452635D01*
Y479069D01*
X78571Y518930D01*
Y664831D01*
X40978Y702424D01*
Y747838D01*
X34417Y754399D01*
X30611D01*
X27363Y757647D01*
X23580D01*
X18360Y762867D01*
Y775418D01*
X15547Y778231D01*
G01Y786105D02*
X17879D01*
X20960Y783024D01*
Y767872D01*
X22970Y765862D01*
X27591D01*
X31585Y761868D01*
X35120D01*
X43578Y753410D01*
Y703502D01*
X81171Y665909D01*
Y517852D01*
X41310Y477991D01*
Y453714D01*
X61655Y433369D01*
Y411249D01*
X47623Y397217D01*
Y263201D01*
X71613Y239211D01*
Y158633D01*
X42334Y129354D01*
Y52842D01*
X47735Y47441D01*
Y24953D01*
G01X7673Y790041D02*
X17099D01*
X22260Y784880D01*
Y768411D01*
X23509Y767162D01*
X28130D01*
X32124Y763168D01*
X35659D01*
X44878Y753949D01*
Y704041D01*
X82471Y666448D01*
Y517313D01*
X42610Y477452D01*
Y454253D01*
X62955Y433908D01*
Y409916D01*
X48923Y395884D01*
Y263740D01*
X72913Y239750D01*
Y158094D01*
X43634Y128815D01*
Y54617D01*
X52735Y45516D01*
Y34953D01*
G01X7673Y782167D02*
X17539D01*
X19660Y780046D01*
Y763406D01*
X24119Y758947D01*
X27902D01*
X31150Y755699D01*
X34957D01*
X42278Y748378D01*
Y702963D01*
X79871Y665370D01*
Y518391D01*
X40010Y478530D01*
Y453174D01*
X60355Y432829D01*
Y411788D01*
X46323Y397756D01*
Y262662D01*
X70313Y238672D01*
Y159172D01*
X41034Y129893D01*
Y52302D01*
X42735Y50601D01*
Y34953D01*
G01X119920Y68071D02*
X114503Y73488D01*
Y81983D01*
X94848Y101638D01*
Y350137D01*
X86015Y358970D01*
Y415704D01*
X89827Y419516D01*
Y663525D01*
X55040Y698312D01*
Y774249D01*
X44131Y785158D01*
X30665D01*
X26789Y789034D01*
X23654D01*
X20118Y792570D01*
Y844526D01*
X15547Y849097D01*
G01X93223Y417736D02*
X91173Y419786D01*
Y664206D01*
X56363Y699016D01*
Y776162D01*
X45364Y787161D01*
X31872D01*
X28234Y790799D01*
X24143D01*
X22357Y792585D01*
Y846244D01*
X16723Y851878D01*
X14391D01*
X7673Y845160D01*
G01X308057Y248863D02*
Y253702D01*
X210046Y351713D01*
X117031D01*
X101348Y367396D01*
Y398363D01*
X102981Y399996D01*
Y407639D01*
X106004Y410662D01*
Y421717D01*
X107640Y423353D01*
Y429382D01*
X104932Y432090D01*
Y673150D01*
X71742Y706340D01*
Y779846D01*
X86416Y794520D01*
Y841207D01*
X53026Y874597D01*
Y883138D01*
X38990Y897174D01*
X31087D01*
X27573Y900688D01*
X13971D01*
X13561Y900278D01*
X7673D01*
G01X15547Y896341D02*
X18411Y899205D01*
X26958D01*
X30472Y895691D01*
X37952D01*
X44229Y889414D01*
Y805301D01*
X70420Y779110D01*
Y705757D01*
X103630Y672547D01*
Y431325D01*
X106340Y428615D01*
Y423892D01*
X104392Y421944D01*
Y410890D01*
X101681Y408179D01*
Y400844D01*
X100029Y399192D01*
Y366810D01*
X116473Y350366D01*
X208952D01*
X304925Y254393D01*
Y242352D01*
X306267Y241010D01*
G01X314940Y252084D02*
X212527Y354497D01*
X118678D01*
X104365Y368810D01*
Y396117D01*
X108604Y400356D01*
Y420639D01*
X110719Y422754D01*
Y430884D01*
X107699Y433904D01*
Y674321D01*
X74387Y707633D01*
Y778308D01*
X89412Y793333D01*
Y862950D01*
X47097Y905265D01*
X31179D01*
X27652Y908792D01*
X14541D01*
X12728Y910605D01*
Y917144D01*
X15547Y919963D01*
G01X329930Y245684D02*
X218288Y357326D01*
X121905D01*
X114067Y365164D01*
Y393472D01*
X111951Y395588D01*
Y413733D01*
X114067Y415849D01*
Y438043D01*
X111047Y441063D01*
Y674975D01*
X77207Y708815D01*
Y776890D01*
X92197Y791880D01*
Y865459D01*
X44839Y912817D01*
X32526D01*
X28564Y916779D01*
X24015D01*
X17849Y922945D01*
X14592D01*
X7673Y916026D01*
G01X320961Y250105D02*
X215177Y355889D01*
X121309D01*
X112767Y364431D01*
Y392933D01*
X110185Y395515D01*
Y415068D01*
X112767Y417650D01*
Y437504D01*
X109404Y440867D01*
Y674585D01*
X75797Y708192D01*
Y777485D01*
X90849Y792537D01*
Y864770D01*
X44347Y911272D01*
X31886D01*
X28099Y915059D01*
X18517D01*
X15547Y912089D01*
G01X305867Y258589D02*
X211259Y353197D01*
X118139D01*
X102648Y368688D01*
Y397010D01*
X107304Y401666D01*
Y421178D01*
X109363Y423237D01*
Y429857D01*
X106282Y432938D01*
Y673899D01*
X73065Y707116D01*
Y779049D01*
X87975Y793959D01*
Y841428D01*
X88112Y841565D01*
Y861683D01*
X45987Y903808D01*
X30682D01*
X27079Y907411D01*
X13076D01*
X12335Y908152D01*
X7673D01*
G01Y971144D02*
X11278Y967539D01*
Y958330D01*
X13475Y956133D01*
X27306D01*
X31372Y960199D01*
X53855D01*
X86572Y927482D01*
Y923294D01*
X104936Y904930D01*
Y769159D01*
X100626Y764849D01*
Y716156D01*
X115271Y701511D01*
X236643D01*
X315890Y622264D01*
Y585526D01*
X319305Y582111D01*
G01X317724Y588250D02*
Y622355D01*
X237207Y702872D01*
X115835D01*
X102058Y716649D01*
Y764080D01*
X106337Y768359D01*
Y905454D01*
X87933Y923858D01*
Y928108D01*
X53136Y962906D01*
X53135D01*
X50020Y966021D01*
X31798D01*
X28206Y962429D01*
X18643D01*
X15547Y959333D01*
G01Y975081D02*
X18761Y971867D01*
X26635D01*
X30507Y975739D01*
X47750D01*
X110802Y912687D01*
Y741887D01*
X113584Y739105D01*
Y714651D01*
X121154Y707081D01*
X238952D01*
X323751Y622282D01*
Y589155D01*
G01X15547Y967207D02*
X18845Y963909D01*
X27136D01*
X30929Y967702D01*
X50210D01*
X89735Y928177D01*
Y924013D01*
X107637Y906111D01*
Y753746D01*
X103910Y750019D01*
Y719250D01*
X118894Y704266D01*
X237785D01*
X319852Y622199D01*
Y593330D01*
G01X7673Y979018D02*
X16631Y970060D01*
X27327D01*
X31365Y974098D01*
X46463D01*
X91172Y929389D01*
Y924476D01*
X109197Y906451D01*
Y740502D01*
X112083Y737616D01*
Y714089D01*
X120469Y705703D01*
X238381D01*
X321742Y622342D01*
Y599041D01*
G01X7673Y955396D02*
X11265D01*
X12335Y954326D01*
X27601D01*
X31988Y958713D01*
X53239D01*
X84170Y927782D01*
Y923819D01*
X103589Y904400D01*
Y769863D01*
X90876Y757150D01*
Y719454D01*
X110174Y700156D01*
X236081D01*
X313511Y622726D01*
Y583360D01*
X320380Y576491D01*
G01X7677Y1061692D02*
X22293D01*
X22588Y1061397D01*
X25486D01*
X29613Y1057270D01*
X49698D01*
X69001Y1037967D01*
X254121D01*
X321425Y970663D01*
Y951577D01*
G01X15551Y1065629D02*
X21336D01*
X24268Y1062697D01*
X26025D01*
X30152Y1058570D01*
X50374D01*
X69580Y1039364D01*
X254983D01*
X324098Y970249D01*
Y946104D01*
G01X326646Y939788D02*
Y970254D01*
X255964Y1040936D01*
X70844D01*
X47011Y1064769D01*
X30717D01*
X26713Y1068773D01*
X13723D01*
X10437Y1072059D01*
Y1074680D01*
X7677Y1077440D01*
G01X328583Y933262D02*
Y944187D01*
X331721Y947325D01*
Y950589D01*
X328583Y953727D01*
Y970156D01*
X256503Y1042236D01*
X71383D01*
X47321Y1066298D01*
X31351D01*
X27347Y1070302D01*
X14357D01*
X12041Y1072618D01*
Y1080950D01*
X7677Y1085314D01*
G01X15551Y1081377D02*
X18756Y1078172D01*
X27706D01*
X31707Y1074171D01*
X43881D01*
X72682Y1045370D01*
X259221D01*
X335825Y968766D01*
Y943534D01*
X339615Y939744D01*
Y926357D01*
G01X15551Y1073503D02*
X18653Y1076605D01*
X26904D01*
X31107Y1072402D01*
X43616D01*
X72086Y1043932D01*
X258167D01*
X330857Y971242D01*
Y953766D01*
X334373Y950250D01*
Y941957D01*
X332414Y939998D01*
Y929350D01*
X333300Y928464D01*
G01X7677Y1124684D02*
X15964D01*
X22700Y1117948D01*
X27476D01*
X30991Y1121463D01*
X36269D01*
X38223Y1123417D01*
X82114D01*
X111227Y1152530D01*
Y1372584D01*
X118235Y1379592D01*
X171502D01*
X179057Y1372037D01*
X234862D01*
X327452Y1279447D01*
G01X15551Y1120748D02*
X20070Y1116229D01*
X28623D01*
X32488Y1120094D01*
X36982D01*
X38956Y1122068D01*
X82673D01*
X112576Y1151971D01*
Y1371518D01*
X118943Y1377885D01*
X170449D01*
X178571Y1369763D01*
X234301D01*
X321978Y1282086D01*
G01X7677Y1140432D02*
X17501D01*
X24356Y1133577D01*
X26738D01*
X30420Y1137259D01*
X38615D01*
X41936Y1133938D01*
X84934D01*
X105783Y1154787D01*
Y1375776D01*
X115567Y1385560D01*
X235086D01*
X338047Y1282599D01*
G01X7677Y1132558D02*
X11147D01*
X11937Y1131768D01*
X16382D01*
X23921Y1124229D01*
X28472D01*
X32121Y1127878D01*
X34852D01*
X35762Y1128788D01*
X85629D01*
X109915Y1153074D01*
Y1373683D01*
X117391Y1381159D01*
X173214D01*
X180563Y1373810D01*
X236241D01*
X333242Y1276809D01*
G01X15551Y1136496D02*
X19544D01*
X23801Y1132239D01*
X28537D01*
X31866Y1135568D01*
X37682D01*
X41222Y1132028D01*
X85133D01*
X107274Y1154169D01*
Y1375158D01*
X116185Y1384069D01*
X176562D01*
X183617Y1377014D01*
X240139D01*
X327932Y1289221D01*
G01X329619Y1284016D02*
X238165Y1375470D01*
X182093D01*
X174794Y1382769D01*
X116724D01*
X108574Y1374619D01*
Y1153630D01*
X85073Y1130129D01*
X35206D01*
X34296Y1129219D01*
X31565D01*
X27916Y1125570D01*
X24477D01*
X16309Y1133738D01*
X13057D01*
X10142Y1136653D01*
X6913D01*
X4862Y1138704D01*
Y1142834D01*
X6398Y1144370D01*
X15551D01*
G01X7677Y1195551D02*
X17000D01*
X19497Y1193054D01*
Y1191669D01*
X22884Y1188282D01*
X27986D01*
X31645Y1184623D01*
X47741D01*
X87661Y1224543D01*
Y1389019D01*
X100086Y1401444D01*
X147972D01*
X151587Y1405059D01*
Y1433850D01*
X176592Y1458855D01*
Y1479439D01*
X265223Y1568070D01*
X320866D01*
X323720Y1570924D01*
G01X329399Y1571939D02*
X322629Y1565169D01*
X264556D01*
X178171Y1478784D01*
Y1458200D01*
X152934Y1432963D01*
Y1404172D01*
X148896Y1400134D01*
X107093D01*
X89240Y1382281D01*
Y1223888D01*
X48485Y1183133D01*
X30954D01*
X27174Y1186913D01*
X20252D01*
X15551Y1191614D01*
G01X7677Y1179803D02*
X13805D01*
X14735Y1178873D01*
X26574D01*
X29994Y1175453D01*
X45355D01*
X91979Y1222077D01*
Y1380404D01*
X108942Y1397367D01*
X150185D01*
X155584Y1402766D01*
Y1431063D01*
X181387Y1456866D01*
Y1477450D01*
X264010Y1560073D01*
X326861D01*
X333474Y1566686D01*
G01X335963Y1573797D02*
X324180Y1562014D01*
X263437D01*
X179610Y1478187D01*
Y1457603D01*
X154256Y1432249D01*
Y1403458D01*
X149493Y1398695D01*
X107887D01*
X90679Y1381487D01*
Y1223291D01*
X44254Y1176866D01*
X30535D01*
X27226Y1180175D01*
X19116D01*
X15551Y1183740D01*
G01X312077Y1575871D02*
X309779Y1573573D01*
X266583D01*
X173663Y1480653D01*
Y1460069D01*
X148939Y1435345D01*
Y1406194D01*
X146803Y1404058D01*
X98557D01*
X85061Y1390562D01*
Y1226087D01*
X51186Y1192212D01*
X31447D01*
X27459Y1196200D01*
X24444D01*
X17219Y1203425D01*
X7677D01*
G01X15551Y1199488D02*
X20444Y1194595D01*
X27013D01*
X30706Y1190902D01*
X51730D01*
X86361Y1225533D01*
Y1390009D01*
X99100Y1402748D01*
X147346D01*
X150249Y1405651D01*
Y1434802D01*
X174973Y1459526D01*
Y1480110D01*
X265751Y1570888D01*
X313299D01*
X317243Y1574832D01*
G01X49441Y1238962D02*
X42211Y1231732D01*
X30110D01*
X22473Y1224095D01*
Y1218156D01*
X25393Y1215236D01*
G01X344402Y1911123D02*
X336551Y1903272D01*
Y1838521D01*
X288697Y1790667D01*
X162665D01*
X155769Y1783771D01*
Y1757441D01*
X143527Y1745199D01*
X120936D01*
X99537Y1723800D01*
Y1495645D01*
X64990Y1461098D01*
Y1275940D01*
X34775Y1245724D01*
X32060D01*
X28430Y1242094D01*
X18787D01*
X15551Y1238858D01*
G01X345537Y1916558D02*
X334898Y1905919D01*
Y1839288D01*
X287988Y1792378D01*
X161956D01*
X154058Y1784480D01*
Y1757924D01*
X143496Y1747362D01*
X120750D01*
X98102Y1724714D01*
Y1496172D01*
X59795Y1457865D01*
Y1291269D01*
X50226Y1281700D01*
Y1263470D01*
X33817Y1247061D01*
X30951D01*
X27741Y1243851D01*
X17695D01*
X16639Y1242795D01*
X7677D01*
G01Y1258543D02*
X10917D01*
X11353Y1258979D01*
X27600D01*
X31504Y1262883D01*
X35209D01*
X44213Y1271887D01*
Y1306597D01*
X51903Y1314287D01*
Y1456217D01*
X93867Y1498181D01*
Y1725996D01*
X120186Y1752315D01*
X141433D01*
X149743Y1760625D01*
Y1786269D01*
X160167Y1796693D01*
X286199D01*
X330249Y1840743D01*
Y1912041D01*
X338309Y1920101D01*
Y1927623D01*
G01X340336Y1922409D02*
Y1919181D01*
X331821Y1910666D01*
Y1840091D01*
X286851Y1795121D01*
X160819D01*
X151315Y1785617D01*
Y1759669D01*
X142389Y1750743D01*
X120453D01*
X95439Y1725729D01*
Y1497529D01*
X53203Y1455293D01*
Y1313748D01*
X45715Y1306260D01*
Y1269770D01*
X37387Y1261442D01*
X32101D01*
X28197Y1257538D01*
X18483D01*
X15551Y1254606D01*
G01X7677Y1250669D02*
X26476D01*
X30739Y1254932D01*
X36979D01*
X47015Y1264968D01*
Y1305721D01*
X54503Y1313209D01*
Y1454722D01*
X96762Y1496981D01*
Y1725213D01*
X120430Y1748881D01*
X142705D01*
X152749Y1758925D01*
Y1785023D01*
X161413Y1793687D01*
X287445D01*
X333531Y1839773D01*
Y1908010D01*
X347676Y1922155D01*
G01X332399Y1926787D02*
Y1917488D01*
X328477Y1913566D01*
Y1841477D01*
X285465Y1798465D01*
X159433D01*
X147971Y1787003D01*
Y1760692D01*
X141178Y1753899D01*
X119931D01*
X92544Y1726512D01*
Y1498699D01*
X50603Y1456758D01*
Y1314826D01*
X42913Y1307136D01*
Y1276888D01*
X35461Y1269436D01*
X31687D01*
X28041Y1265790D01*
X18861D01*
X15551Y1262480D01*
G01Y1270354D02*
X18404Y1267501D01*
X27769D01*
X31004Y1270736D01*
X33705D01*
X41613Y1278644D01*
Y1307675D01*
X49151Y1315213D01*
Y1457264D01*
X86291Y1494404D01*
Y1677245D01*
X45056Y1718480D01*
G01X15551Y1333346D02*
X19028Y1329869D01*
X27921D01*
X30782Y1332730D01*
X40093D01*
X46980Y1325843D01*
G01X7677Y1321535D02*
X28039D01*
X31173Y1318401D01*
X44422D01*
X46980Y1315843D01*
G01X7677Y1353031D02*
X13533D01*
X14180Y1353678D01*
X28388D01*
X34310Y1347756D01*
X45067D01*
X46980Y1345843D01*
G01X15551Y1349094D02*
X18597Y1352140D01*
X27970D01*
X34818Y1345292D01*
X42531D01*
X46980Y1340843D01*
G01X33263Y884530D02*
X35153D01*
X42755Y876928D01*
Y804485D01*
X69008Y778232D01*
Y704606D01*
X102211Y671403D01*
Y430497D01*
X105040Y427668D01*
Y424431D01*
X102773Y422164D01*
Y411111D01*
X95563Y403901D01*
Y368977D01*
X116376Y348164D01*
X206493D01*
X301945Y252712D01*
Y239556D01*
X321296Y220205D01*
X326408D01*
X333974Y212639D01*
Y198542D01*
X338117Y194399D01*
Y67124D01*
X348289Y56952D01*
Y50863D01*
G01X345089Y56190D02*
Y58030D01*
X336817Y66302D01*
Y193860D01*
X332674Y198003D01*
Y212100D01*
X325987Y218787D01*
X320299D01*
X300238Y238848D01*
Y252004D01*
X205785Y346457D01*
X115668D01*
X94088Y368037D01*
Y404265D01*
X101473Y411650D01*
Y422703D01*
X103740Y424970D01*
Y427047D01*
X100819Y429968D01*
Y670822D01*
X67301Y704340D01*
Y778099D01*
X41453Y803947D01*
Y876012D01*
X35959Y881506D01*
X32350D01*
X25389Y888467D01*
G01X338227Y61559D02*
X335517Y64269D01*
Y193321D01*
X331374Y197464D01*
Y210967D01*
X324932Y217409D01*
X319357D01*
X298598Y238168D01*
Y251324D01*
X205105Y344817D01*
X114643D01*
X92621Y366839D01*
Y405298D01*
X100173Y412850D01*
Y424640D01*
X99216Y425597D01*
Y670143D01*
X65784Y703575D01*
Y777777D01*
X40105Y803456D01*
Y875257D01*
X35271Y880091D01*
X25891D01*
X25389Y880593D01*
G01X340373Y51579D02*
Y56290D01*
X334217Y62446D01*
Y192782D01*
X330074Y196925D01*
Y209589D01*
X323679Y215984D01*
X318622D01*
X297071Y237535D01*
Y250691D01*
X204472Y343290D01*
X112613D01*
X91321Y364582D01*
Y406626D01*
X98873Y414178D01*
Y424034D01*
X97857Y425050D01*
Y669292D01*
X64238Y702911D01*
Y777483D01*
X38713Y803008D01*
Y871206D01*
X33263Y876656D01*
G01Y868782D02*
X36019Y866026D01*
Y802024D01*
X61371Y776672D01*
Y701885D01*
X95257Y667999D01*
Y423972D01*
X96273Y422956D01*
Y415256D01*
X88721Y407704D01*
Y361879D01*
X111114Y339486D01*
X202895D01*
X293267Y249114D01*
Y235958D01*
X316739Y212486D01*
X322733D01*
X327474Y207745D01*
Y195847D01*
X331403Y191918D01*
Y51409D01*
G01X25389Y864845D02*
Y866081D01*
X31406Y872098D01*
X34619D01*
X37366Y869351D01*
Y802516D01*
X62833Y777049D01*
Y702329D01*
X96557Y668605D01*
Y424511D01*
X97573Y423495D01*
Y414717D01*
X90021Y407165D01*
Y363146D01*
X111811Y341356D01*
X203670D01*
X295137Y249889D01*
Y236733D01*
X317848Y214022D01*
X323037D01*
X328774Y208285D01*
Y196386D01*
X332917Y192243D01*
Y61838D01*
X333889Y60866D01*
Y56021D01*
G01X25389Y849097D02*
X28579Y845907D01*
Y795980D01*
X31475Y793084D01*
X41280D01*
X57773Y776591D01*
Y699720D01*
X92565Y664928D01*
Y420869D01*
X94973Y418461D01*
Y415795D01*
X87421Y408243D01*
Y359403D01*
X96165Y350659D01*
Y102971D01*
X116772Y82364D01*
X127305D01*
X130072Y79597D01*
Y67907D01*
X139908Y58071D01*
X139920D01*
G01X33263Y845160D02*
X30199Y842096D01*
Y796848D01*
X32343Y794704D01*
X41500D01*
X59448Y776756D01*
Y700022D01*
X93957Y665513D01*
Y421952D01*
X94347Y421562D01*
G01X323313Y418313D02*
Y445427D01*
X331204Y453318D01*
Y538019D01*
X328223Y541000D01*
Y558995D01*
X321306Y565912D01*
X319966D01*
X305142Y580736D01*
Y618941D01*
X230625Y693458D01*
X104208D01*
X82575Y715091D01*
Y775501D01*
X96463Y789389D01*
Y881159D01*
X76417Y901205D01*
Y906459D01*
X61035Y921841D01*
X36074D01*
X34196Y919963D01*
X25389D01*
G01X320980Y423225D02*
Y444961D01*
X329884Y453865D01*
Y537472D01*
X326903Y540453D01*
Y558448D01*
X320759Y564592D01*
X319419D01*
X303822Y580189D01*
Y618394D01*
X230078Y692138D01*
X101666D01*
X80330Y713474D01*
Y775863D01*
X95116Y790649D01*
Y880576D01*
X75097Y900595D01*
Y905912D01*
X61048Y919961D01*
X37198D01*
X33263Y916026D01*
G01Y923900D02*
X61449D01*
X77733Y907616D01*
Y901865D01*
X97959Y881639D01*
Y788549D01*
X84192Y774782D01*
Y716214D01*
X105632Y694774D01*
X231171D01*
X306458Y619487D01*
Y581282D01*
X320512Y567228D01*
X321852D01*
X329539Y559541D01*
Y541546D01*
X332520Y538565D01*
Y452772D01*
X326196Y446448D01*
Y413982D01*
G01X25389Y935711D02*
X54282D01*
X81070Y908923D01*
Y903303D01*
X100802Y883571D01*
Y786586D01*
X87785Y773569D01*
Y717516D01*
X107808Y697493D01*
X232298D01*
X309177Y620614D01*
Y582409D01*
X321639Y569947D01*
X322979D01*
X332258Y560668D01*
Y542673D01*
X335239Y539692D01*
Y451645D01*
X331786Y448192D01*
Y407769D01*
X335522Y404033D01*
G01X33263Y939648D02*
X52632D01*
X82687Y909593D01*
Y903973D01*
X102239Y884421D01*
Y785957D01*
X89402Y773120D01*
Y718638D01*
X109194Y698846D01*
X232859D01*
X310530Y621175D01*
Y582970D01*
X322200Y571300D01*
X323540D01*
X333611Y561229D01*
Y543234D01*
X336592Y540253D01*
Y451084D01*
X333834Y448326D01*
Y409947D01*
X342097Y401684D01*
G01X25389Y927837D02*
X59818D01*
X79363Y908292D01*
Y902886D01*
X99425Y882824D01*
Y787455D01*
X85899Y773929D01*
Y716662D01*
X106422Y696139D01*
X231737D01*
X307823Y620053D01*
Y581848D01*
X321078Y568593D01*
X322418D01*
X330904Y560107D01*
Y542112D01*
X333885Y539131D01*
Y452206D01*
X328950Y447271D01*
Y409216D01*
G01X331568Y752967D02*
Y791869D01*
X335094Y795395D01*
Y847696D01*
X329738Y853052D01*
Y911721D01*
X311815Y929644D01*
Y970930D01*
X257311Y1025434D01*
X186346D01*
X182041Y1029739D01*
X170503D01*
X168476Y1031766D01*
X67013D01*
X46362Y1011115D01*
Y1006544D01*
X34584Y994766D01*
X33263D01*
G01X329336Y762693D02*
Y792266D01*
X333486Y796416D01*
Y847335D01*
X328281Y852540D01*
Y910790D01*
X310127Y928944D01*
Y970230D01*
X257495Y1022863D01*
X256327Y1024031D01*
X184859D01*
X180727Y1028163D01*
X169914D01*
X167999Y1030078D01*
X67165D01*
X48050Y1010963D01*
Y1005078D01*
X29996Y987024D01*
Y979688D01*
X25389Y975081D01*
G01Y990829D02*
X29731Y995171D01*
Y995833D01*
X31694Y997796D01*
X34927D01*
X44898Y1007767D01*
Y1011491D01*
X67070Y1033663D01*
X184070D01*
X190837Y1026896D01*
X257921D01*
X313279Y971537D01*
Y930251D01*
X331202Y912328D01*
Y853794D01*
X336558Y848438D01*
Y794252D01*
X334010Y791704D01*
Y758588D01*
G01X33263Y979018D02*
Y987722D01*
X49866Y1004325D01*
Y1010939D01*
X67189Y1028262D01*
X167214D01*
X168731Y1026745D01*
X178901D01*
X182969Y1022677D01*
X255112D01*
X308311Y969477D01*
Y928036D01*
X326518Y909829D01*
Y851862D01*
X331819Y846561D01*
Y797624D01*
X327524Y793329D01*
Y758020D01*
G01X33263Y1002640D02*
X40539Y1009916D01*
Y1013292D01*
X63661Y1036414D01*
X252295D01*
X316030Y972678D01*
Y931392D01*
X333953Y913469D01*
Y855258D01*
X339231Y849980D01*
Y756687D01*
X344109Y751809D01*
G01X339012Y752859D02*
X337925Y753946D01*
Y849351D01*
X332569Y854707D01*
Y912895D01*
X314646Y930818D01*
Y972104D01*
X258089Y1028662D01*
X191985D01*
X185617Y1035030D01*
X65632D01*
X42944Y1012342D01*
Y1008173D01*
X34496Y999725D01*
X30361D01*
X29339Y998703D01*
X25389D01*
G01X25393Y1097125D02*
X34335Y1088183D01*
X48899D01*
X83820Y1053262D01*
X309678D01*
G01X25393Y1089251D02*
X32689Y1081955D01*
X41915D01*
X74220Y1049650D01*
X322110D01*
X324246Y1051786D01*
G01X33267Y1077440D02*
X42656D01*
X73281Y1046815D01*
X344549D01*
X345578Y1047844D01*
G01X25393Y1081377D02*
X30119D01*
X31146Y1080350D01*
X41603D01*
X73825Y1048128D01*
X334902D01*
X335677Y1048903D01*
G01X33267Y1101062D02*
X43776Y1090553D01*
X52261D01*
X82763Y1060051D01*
G01X33267Y1085314D02*
X49628D01*
X83992Y1050950D01*
X315492D01*
X317592Y1053050D01*
G01X33267Y1148306D02*
X38212D01*
X47760Y1138758D01*
X82286D01*
X97226Y1153698D01*
Y1376705D01*
X112449Y1391928D01*
X165692D01*
X168425Y1394661D01*
Y1394663D01*
X176083Y1402321D01*
G01X25393Y1136496D02*
X32445Y1143548D01*
X38022D01*
X44730Y1136840D01*
X82858D01*
X102967Y1156949D01*
Y1380156D01*
X113358Y1390547D01*
X170204D01*
X185978Y1406321D01*
X329129D01*
X334646Y1400804D01*
G01X25393Y1144370D02*
X32908Y1151885D01*
X36753D01*
X48381Y1140257D01*
X81665D01*
X95926Y1154518D01*
Y1377377D01*
X111937Y1393388D01*
X162395D01*
X170351Y1401344D01*
G01X33267Y1140432D02*
X38297D01*
X43251Y1135478D01*
X83452D01*
X104350Y1156376D01*
Y1377014D01*
X116561Y1389225D01*
X171594D01*
X180708Y1398339D01*
X321062D01*
X323655Y1400932D01*
X327757D01*
X330350Y1398339D01*
X340799D01*
X344130Y1401670D01*
G01X25393Y1160118D02*
X37731D01*
X54725Y1143124D01*
X80477D01*
X93279Y1155926D01*
Y1378924D01*
X110400Y1396045D01*
X155129D01*
X156364Y1397280D01*
X156450D01*
X158618Y1399448D01*
G01X33267Y1156180D02*
X39642D01*
X54131Y1141691D01*
X81071D01*
X94626Y1155246D01*
Y1378194D01*
X111155Y1394723D01*
X158534D01*
X164037Y1400226D01*
G01X33267Y1195551D02*
X43419D01*
X83761Y1235893D01*
Y1462511D01*
X113923Y1492673D01*
Y1720524D01*
X122691Y1729292D01*
X166635D01*
X173394Y1736051D01*
G01X33267Y1203425D02*
X45273D01*
X81161Y1239313D01*
Y1463993D01*
X111111Y1493943D01*
Y1721782D01*
X121495Y1732166D01*
X161109D01*
X168151Y1739208D01*
G01X25393Y1199488D02*
X44432D01*
X82461Y1237517D01*
Y1463367D01*
X112582Y1493488D01*
Y1721351D01*
X121823Y1730592D01*
X163472D01*
X165782Y1732902D01*
G01X25393Y1207362D02*
X47056D01*
X79861Y1240167D01*
Y1464847D01*
X109588Y1494574D01*
Y1722413D01*
X120641Y1733466D01*
X159104D01*
X163257Y1737619D01*
G01X33267Y1227047D02*
X37204Y1223110D01*
X52558D01*
X77261Y1247813D01*
Y1466289D01*
X106654Y1495682D01*
Y1723359D01*
X120304Y1737009D01*
X150309D01*
G01X25393Y1223110D02*
X32525Y1230242D01*
X43196D01*
X63815Y1250861D01*
Y1263898D01*
X73725Y1273808D01*
Y1465734D01*
X105354Y1497363D01*
Y1724518D01*
X119697Y1738861D01*
X144878D01*
G01X33267Y1219173D02*
X51338D01*
X78561Y1246396D01*
Y1465434D01*
X108131Y1495004D01*
Y1722799D01*
X120572Y1735240D01*
X156183D01*
G01X25393Y1325472D02*
X42351D01*
X46980Y1320843D01*
G01Y1330843D02*
X40540Y1337283D01*
X33267D01*
G01X114498Y396207D02*
Y412521D01*
X115803Y413826D01*
Y439620D01*
X114065Y441358D01*
Y674145D01*
X78882Y709328D01*
Y776435D01*
X93634Y791187D01*
Y872495D01*
X75156Y890973D01*
Y893459D01*
X70865Y897750D01*
G01X49441Y1238962D02*
X61708Y1251229D01*
Y1264771D01*
X69568Y1272631D01*
Y1463510D01*
X103782Y1497724D01*
Y1725170D01*
X121700Y1743088D01*
X154759D01*
X176441Y1764770D01*
X322273D01*
X328072Y1770569D01*
Y1781159D01*
X336284Y1789371D01*
X348511D01*
X353177Y1784705D01*
X357165D01*
G01X82763Y1060051D02*
X87340Y1055474D01*
X314654D01*
X331376Y1072196D01*
Y1089549D01*
X335208Y1093381D01*
X353546D01*
X362165Y1084762D01*
Y1079705D01*
G01X100719Y1346065D02*
X98526Y1343872D01*
Y1315003D01*
X100719Y1312810D01*
G01X337165Y1784705D02*
X329483Y1777023D01*
Y1769433D01*
X322582Y1762532D01*
X177654D01*
X153983Y1738861D01*
X144878D01*
G01X158618Y1399448D02*
X173912Y1414742D01*
X325375D01*
X329594Y1418961D01*
Y1435011D01*
X334981Y1440398D01*
X357126D01*
X362165Y1435359D01*
Y1429705D01*
G01X164037Y1400226D02*
X176827Y1413016D01*
X326261D01*
X331276Y1418031D01*
Y1434807D01*
X335185Y1438716D01*
X353154D01*
X357165Y1434705D01*
G01X342165Y1779705D02*
X335371D01*
X330860Y1775194D01*
Y1768042D01*
X323378Y1760560D01*
X180035D01*
X156484Y1737009D01*
X150309D01*
G01X168151Y1739208D02*
X185109Y1756166D01*
X333875D01*
X345763Y1768054D01*
Y1770976D01*
X343818Y1772921D01*
X338949D01*
X337165Y1774705D01*
G01X362165Y1779705D02*
X357548D01*
X354053Y1776210D01*
X350538D01*
X348245Y1778503D01*
X346029D01*
X342961Y1775435D01*
X340936D01*
X338253Y1778118D01*
X336076D01*
X333057Y1775099D01*
Y1768050D01*
X324204Y1759197D01*
X181139D01*
X157182Y1735240D01*
X156183D01*
G01X165782Y1732902D02*
X181211Y1748331D01*
X340791D01*
X362165Y1769705D01*
G01X165782Y1732902D02*
Y1732903D01*
G01X163257Y1737619D02*
X183488Y1757850D01*
X333130D01*
X342165Y1766885D01*
Y1769705D01*
G01X176083Y1402321D02*
X179681Y1405919D01*
X179683D01*
X182611Y1408847D01*
X331307D01*
X342165Y1419705D01*
G01X170351Y1401344D02*
X179959Y1410952D01*
X328247D01*
X337165Y1419870D01*
Y1424705D01*
G01X170351Y1401344D02*
Y1401324D01*
G01X357165Y1774705D02*
X362030D01*
X365899Y1770836D01*
Y1768951D01*
X343471Y1746523D01*
X183866D01*
X173394Y1736051D01*
G01X308057Y248863D02*
X321510Y235410D01*
Y231579D01*
X323588Y229501D01*
X328414D01*
X340130Y217785D01*
Y213672D01*
X340978Y212824D01*
Y205934D01*
X342186Y204726D01*
X342165Y204705D01*
G01X337165Y209705D02*
Y217329D01*
X326490Y228004D01*
X319273D01*
X306267Y241010D01*
G01X352165Y194705D02*
X350957Y195913D01*
X346524D01*
X343620Y198817D01*
Y201147D01*
X345359Y202886D01*
Y206487D01*
X343268Y208578D01*
Y212979D01*
X342454Y213793D01*
Y217959D01*
X326351Y234062D01*
Y238105D01*
X305867Y258589D01*
G01X309678Y1053262D02*
X314366D01*
X332990Y1071886D01*
Y1088880D01*
X335600Y1091490D01*
X350380D01*
X357165Y1084705D01*
G01X347165Y1609705D02*
X341860D01*
X331394Y1599239D01*
Y1595188D01*
X312077Y1575871D01*
G01X337165Y24705D02*
Y30117D01*
X340373Y33325D01*
Y51579D01*
G01X331403Y51409D02*
Y22773D01*
X338999Y15177D01*
X357637D01*
X362165Y19705D01*
G01X333889Y56021D02*
Y22656D01*
X339992Y16553D01*
X353709D01*
X357165Y20009D01*
Y24705D01*
G01X342165Y19705D02*
Y25030D01*
X345685Y28550D01*
Y31569D01*
X342731Y34523D01*
Y57055D01*
X338227Y61559D01*
G01X314940Y252084D02*
X344399Y222625D01*
Y215788D01*
X347165Y213022D01*
Y209705D01*
G01X352165Y204705D02*
Y214547D01*
X349190Y217522D01*
Y226424D01*
X329930Y245684D01*
G01X320961Y250105D02*
X346344Y224722D01*
Y216399D01*
X350309Y212434D01*
Y207982D01*
X348819Y206492D01*
Y201359D01*
X347165Y199705D01*
G01X314940Y252083D02*
Y252084D01*
G01X362165Y369705D02*
X356430Y363970D01*
X339253D01*
X329791Y373432D01*
Y397570D01*
X323313Y404048D01*
Y418313D01*
G01X320980Y423225D02*
Y403265D01*
X328003Y396242D01*
Y373353D01*
X338706Y362650D01*
X361692D01*
X366517Y367475D01*
Y371067D01*
X362879Y374705D01*
X357165D01*
G01X326196Y413982D02*
Y405259D01*
X332044Y399411D01*
Y384882D01*
X337167Y379759D01*
Y374707D01*
X337165Y374705D01*
G01X335522Y404033D02*
X354850Y384705D01*
X357165D01*
G01X342165Y369705D02*
X342167Y369707D01*
Y375104D01*
X345215Y378152D01*
Y382080D01*
X343200Y384095D01*
Y391909D01*
X328950Y406159D01*
Y409216D01*
G01X319305Y582111D02*
X340711Y560705D01*
Y558500D01*
X338462Y556251D01*
Y553326D01*
X342083Y549705D01*
X347166D01*
G01X320380Y576491D02*
X337166Y559705D01*
G01X317724Y588250D02*
Y586292D01*
X342166Y561850D01*
Y554705D01*
G01X352166D02*
Y557240D01*
X350495Y558911D01*
Y560690D01*
X323751Y587434D01*
Y589155D01*
G01X319852Y593330D02*
Y586488D01*
X343578Y562762D01*
Y558308D01*
X352166Y549720D01*
Y544705D01*
G01X347166Y559705D02*
Y561852D01*
X321742Y587276D01*
Y599041D01*
G01X331568Y752967D02*
Y723878D01*
X335741Y719705D01*
X342166D01*
G01X357166Y724705D02*
Y718067D01*
X355198Y716099D01*
X337099D01*
X329336Y723862D01*
Y762693D01*
G01X337166Y724705D02*
X334010Y727861D01*
Y758588D01*
G01X362166Y719705D02*
X356893Y714432D01*
X336408D01*
X327524Y723316D01*
Y758020D01*
G01X339012Y752859D02*
X357166Y734705D01*
G01X321425Y951577D02*
X320372Y950524D01*
Y928963D01*
X337165Y912170D01*
Y909705D01*
G01X324098Y946104D02*
Y938250D01*
X321888Y936040D01*
Y929347D01*
X342130Y909105D01*
Y904740D01*
X342165Y904705D01*
G01X347165Y899705D02*
X347130Y899740D01*
Y905078D01*
X343752Y908456D01*
Y910600D01*
X326646Y927706D01*
Y939788D01*
G01X352165Y894705D02*
X352130Y894740D01*
Y899818D01*
X348692Y903256D01*
Y906175D01*
X350309Y907792D01*
Y911455D01*
X333300Y928464D01*
G01X328583Y933262D02*
Y928287D01*
X347165Y909705D01*
G01X324246Y1051786D02*
X342165Y1069705D01*
G01X362165D02*
X356479D01*
X335677Y1048903D01*
G01D02*
Y1048904D01*
G01X337165Y1074705D02*
Y1072623D01*
X317592Y1053050D01*
G01X337165Y1259705D02*
Y1266899D01*
X321978Y1282086D01*
G01X342165Y1254705D02*
Y1257901D01*
X340678Y1259388D01*
Y1266221D01*
X327452Y1279447D01*
G01X352165Y1254705D02*
Y1268481D01*
X338047Y1282599D01*
G01X333242Y1276809D02*
X343376Y1266675D01*
Y1258552D01*
X345404Y1256524D01*
Y1252879D01*
X343908Y1251383D01*
Y1248232D01*
X347435Y1244705D01*
X352165D01*
G01X347165Y1249705D02*
Y1255190D01*
X350447Y1258472D01*
Y1266706D01*
X327932Y1289221D01*
G01X347165Y1259705D02*
Y1266470D01*
X329619Y1284016D01*
G01X334646Y1400804D02*
X338426D01*
X357165Y1419543D01*
Y1424705D01*
G01X323720Y1570924D02*
X347165Y1594369D01*
Y1599705D01*
G01X329399Y1571939D02*
X352165Y1594705D01*
G01Y1604705D02*
X347116D01*
X317243Y1574832D01*
G01X333474Y1566686D02*
X358639Y1591851D01*
Y1595862D01*
X360282Y1597505D01*
Y1601631D01*
X358334Y1603579D01*
Y1605911D01*
X360224Y1607801D01*
Y1611776D01*
X358701Y1613299D01*
X340759D01*
X337165Y1609705D01*
G01X335963Y1573797D02*
X355505Y1593339D01*
Y1596703D01*
X353900Y1598308D01*
Y1601326D01*
X356155Y1603581D01*
Y1605873D01*
X354054Y1607974D01*
X350805D01*
X349353Y1606522D01*
X343982D01*
X342165Y1604705D01*
G01X352165Y1954705D02*
X349220D01*
X347749Y1953234D01*
X345684D01*
X338309Y1945859D01*
Y1927623D01*
G01X347165Y1959705D02*
X342316D01*
X332399Y1949788D01*
Y1926787D01*
G01X344402Y1911123D02*
X364941Y1931662D01*
Y1940969D01*
X365937Y1941965D01*
Y1956711D01*
X358621Y1964027D01*
X341487D01*
X337165Y1959705D01*
G01X362165Y29705D02*
X357371D01*
X345089Y41987D01*
Y56190D01*
G01X348289Y50863D02*
Y43581D01*
X357165Y34705D01*
G01X362165Y379705D02*
Y384045D01*
X358140Y388070D01*
X355711D01*
X342097Y401684D01*
G01X344109Y751809D02*
X356176Y739742D01*
X356443D01*
X362166Y734019D01*
Y729705D01*
G01X339615Y926357D02*
X352130Y913842D01*
Y904740D01*
X352165Y904705D01*
G01X357165Y1074705D02*
X362525D01*
X365595Y1071635D01*
Y1067861D01*
X345578Y1047844D01*
G01X344130Y1401670D02*
X362165Y1419705D01*
G01X345537Y1916558D02*
X355429Y1926450D01*
Y1946553D01*
X354093Y1947889D01*
Y1951248D01*
X355965Y1953120D01*
Y1955986D01*
X353366Y1958585D01*
X350883D01*
X347003Y1954705D01*
X342165D01*
G01X347165Y1949705D02*
Y1929238D01*
X340336Y1922409D01*
G01X352165Y1944705D02*
Y1926644D01*
X347676Y1922155D01*
G01D02*
Y1922165D01*
G54D18*
G01X-723776Y2987387D02*
Y-376795D01*
Y-489221D01*
X1782976D01*
Y-376795D01*
Y2987387D01*
X-723776D01*
G01X-4000Y-62500D02*
Y-137500D01*
X496000D01*
Y-62500D01*
X-4000D01*
G01X8000Y-127500D02*
Y-132500D01*
G01X6543Y-127500D02*
X9457D01*
G01X14367Y-132500D02*
X11833D01*
Y-127500D01*
X14367D01*
G01X13353Y-129917D02*
X11833D01*
G01X16933Y-127500D02*
Y-132500D01*
X19467D01*
G01X23300Y-132667D02*
X23173Y-132583D01*
Y-132417D01*
X23300Y-132333D01*
X23427Y-132417D01*
Y-132583D01*
X23300Y-132667D01*
G01Y-130417D02*
X23173Y-130333D01*
Y-130167D01*
X23300Y-130083D01*
X23427Y-130167D01*
Y-130333D01*
X23300Y-130417D01*
G01X28083Y-134167D02*
X27450Y-133333D01*
X27133Y-132500D01*
Y-129167D01*
X27450Y-128333D01*
X28083Y-127500D01*
G01X33500D02*
X32993Y-127667D01*
X32613Y-128083D01*
X32360Y-128583D01*
X32170Y-129250D01*
X32107Y-130000D01*
X32170Y-130750D01*
X32360Y-131417D01*
X32613Y-131917D01*
X32993Y-132333D01*
X33500Y-132500D01*
X34007Y-132333D01*
X34387Y-131917D01*
X34640Y-131417D01*
X34830Y-130750D01*
X34893Y-130000D01*
X34830Y-129250D01*
X34640Y-128583D01*
X34387Y-128083D01*
X34007Y-127667D01*
X33500Y-127500D01*
G01X37207Y-131500D02*
X37587Y-132083D01*
X38093Y-132417D01*
X38663Y-132500D01*
X39170Y-132417D01*
X39677Y-132000D01*
X39993Y-131500D01*
X40057Y-131000D01*
X39930Y-130417D01*
X39487Y-130000D01*
X39043Y-129833D01*
X38473D01*
G01X39043D02*
X39423Y-129583D01*
X39740Y-129167D01*
X39867Y-128667D01*
X39740Y-128167D01*
X39423Y-127750D01*
X38853Y-127500D01*
X38283Y-127583D01*
X37713Y-127917D01*
G01X44017Y-134167D02*
X44650Y-133333D01*
X44967Y-132500D01*
Y-129167D01*
X44650Y-128333D01*
X44017Y-127500D01*
G01X47407Y-131500D02*
X47787Y-132083D01*
X48293Y-132417D01*
X48863Y-132500D01*
X49370Y-132417D01*
X49877Y-132000D01*
X50193Y-131500D01*
X50257Y-131000D01*
X50130Y-130417D01*
X49687Y-130000D01*
X49243Y-129833D01*
X48673D01*
G01X49243D02*
X49623Y-129583D01*
X49940Y-129167D01*
X50067Y-128667D01*
X49940Y-128167D01*
X49623Y-127750D01*
X49053Y-127500D01*
X48483Y-127583D01*
X47913Y-127917D01*
G01X52697Y-128333D02*
X53077Y-127833D01*
X53520Y-127583D01*
X54027Y-127500D01*
X54660Y-127667D01*
X55103Y-128083D01*
X55230Y-128583D01*
X55167Y-129083D01*
X54913Y-129500D01*
X53647Y-130333D01*
X53077Y-130917D01*
X52697Y-131750D01*
X52570Y-132500D01*
X55230D01*
G01X58873D02*
X59000Y-131417D01*
X59190Y-130500D01*
X59443Y-129667D01*
X59760Y-128750D01*
X60267Y-127500D01*
X57733D01*
G01X63277Y-130833D02*
X64923D01*
G01X67997Y-128333D02*
X68377Y-127833D01*
X68820Y-127583D01*
X69327Y-127500D01*
X69960Y-127667D01*
X70403Y-128083D01*
X70530Y-128583D01*
X70467Y-129083D01*
X70213Y-129500D01*
X68947Y-130333D01*
X68377Y-130917D01*
X67997Y-131750D01*
X67870Y-132500D01*
X70530D01*
G01X72907Y-131500D02*
X73287Y-132083D01*
X73793Y-132417D01*
X74363Y-132500D01*
X74870Y-132417D01*
X75377Y-132000D01*
X75693Y-131500D01*
X75757Y-131000D01*
X75630Y-130417D01*
X75187Y-130000D01*
X74743Y-129833D01*
X74173D01*
G01X74743D02*
X75123Y-129583D01*
X75440Y-129167D01*
X75567Y-128667D01*
X75440Y-128167D01*
X75123Y-127750D01*
X74553Y-127500D01*
X73983Y-127583D01*
X73413Y-127917D01*
G01X80160Y-132500D02*
Y-127500D01*
X77817Y-131083D01*
X80983D01*
G01X83107Y-131750D02*
X83487Y-132167D01*
X83930Y-132417D01*
X84500Y-132500D01*
X85070Y-132333D01*
X85513Y-132000D01*
X85830Y-131417D01*
X85893Y-130750D01*
X85767Y-130083D01*
X85450Y-129667D01*
X85007Y-129333D01*
X84563Y-129250D01*
X84120Y-129333D01*
X83550Y-129667D01*
X83740Y-127500D01*
X85450D01*
G01X93497Y-132500D02*
Y-127500D01*
X95903D01*
G01X95017Y-129917D02*
X93497D01*
G01X98217Y-132500D02*
X99800Y-127500D01*
X101383Y-132500D01*
G01X100813Y-130750D02*
X98787D01*
G01X103570Y-132500D02*
X106230Y-127500D01*
G01X103570D02*
X106230Y-132500D01*
G01X110000Y-132667D02*
X109873Y-132583D01*
Y-132417D01*
X110000Y-132333D01*
X110127Y-132417D01*
Y-132583D01*
X110000Y-132667D01*
G01Y-130417D02*
X109873Y-130333D01*
Y-130167D01*
X110000Y-130083D01*
X110127Y-130167D01*
Y-130333D01*
X110000Y-130417D01*
G01X114783Y-134167D02*
X114150Y-133333D01*
X113833Y-132500D01*
Y-129167D01*
X114150Y-128333D01*
X114783Y-127500D01*
G01X120200D02*
X119693Y-127667D01*
X119313Y-128083D01*
X119060Y-128583D01*
X118870Y-129250D01*
X118807Y-130000D01*
X118870Y-130750D01*
X119060Y-131417D01*
X119313Y-131917D01*
X119693Y-132333D01*
X120200Y-132500D01*
X120707Y-132333D01*
X121087Y-131917D01*
X121340Y-131417D01*
X121530Y-130750D01*
X121593Y-130000D01*
X121530Y-129250D01*
X121340Y-128583D01*
X121087Y-128083D01*
X120707Y-127667D01*
X120200Y-127500D01*
G01X123907Y-131500D02*
X124287Y-132083D01*
X124793Y-132417D01*
X125363Y-132500D01*
X125870Y-132417D01*
X126377Y-132000D01*
X126693Y-131500D01*
X126757Y-131000D01*
X126630Y-130417D01*
X126187Y-130000D01*
X125743Y-129833D01*
X125173D01*
G01X125743D02*
X126123Y-129583D01*
X126440Y-129167D01*
X126567Y-128667D01*
X126440Y-128167D01*
X126123Y-127750D01*
X125553Y-127500D01*
X124983Y-127583D01*
X124413Y-127917D01*
G01X130717Y-134167D02*
X131350Y-133333D01*
X131667Y-132500D01*
Y-129167D01*
X131350Y-128333D01*
X130717Y-127500D01*
G01X134107Y-131500D02*
X134487Y-132083D01*
X134993Y-132417D01*
X135563Y-132500D01*
X136070Y-132417D01*
X136577Y-132000D01*
X136893Y-131500D01*
X136957Y-131000D01*
X136830Y-130417D01*
X136387Y-130000D01*
X135943Y-129833D01*
X135373D01*
G01X135943D02*
X136323Y-129583D01*
X136640Y-129167D01*
X136767Y-128667D01*
X136640Y-128167D01*
X136323Y-127750D01*
X135753Y-127500D01*
X135183Y-127583D01*
X134613Y-127917D01*
G01X139523Y-131917D02*
X139967Y-132333D01*
X140473Y-132500D01*
X140980Y-132333D01*
X141423Y-131833D01*
X141740Y-131083D01*
X141867Y-130333D01*
Y-129417D01*
X141740Y-128667D01*
X141423Y-128000D01*
X141043Y-127667D01*
X140600Y-127500D01*
X140093Y-127667D01*
X139713Y-128000D01*
X139460Y-128500D01*
X139333Y-129167D01*
X139460Y-129750D01*
X139777Y-130333D01*
X140157Y-130667D01*
X140600Y-130750D01*
X141107Y-130583D01*
X141487Y-130167D01*
X141867Y-129417D01*
G01X145573Y-132500D02*
X145700Y-131417D01*
X145890Y-130500D01*
X146143Y-129667D01*
X146460Y-128750D01*
X146967Y-127500D01*
X144433D01*
G01X149977Y-130833D02*
X151623D01*
G01X154507Y-131500D02*
X154887Y-132083D01*
X155393Y-132417D01*
X155963Y-132500D01*
X156470Y-132417D01*
X156977Y-132000D01*
X157293Y-131500D01*
X157357Y-131000D01*
X157230Y-130417D01*
X156787Y-130000D01*
X156343Y-129833D01*
X155773D01*
G01X156343D02*
X156723Y-129583D01*
X157040Y-129167D01*
X157167Y-128667D01*
X157040Y-128167D01*
X156723Y-127750D01*
X156153Y-127500D01*
X155583Y-127583D01*
X155013Y-127917D01*
G01X159797Y-130417D02*
X160240Y-129833D01*
X160620Y-129500D01*
X161127Y-129333D01*
X161570Y-129500D01*
X161887Y-129833D01*
X162140Y-130333D01*
X162203Y-130917D01*
X162140Y-131417D01*
X161887Y-131917D01*
X161507Y-132333D01*
X161063Y-132500D01*
X160557Y-132333D01*
X160113Y-131833D01*
X159860Y-131083D01*
X159797Y-130250D01*
X159923Y-129167D01*
X160113Y-128583D01*
X160430Y-128000D01*
X160873Y-127583D01*
X161317Y-127500D01*
X161760Y-127667D01*
X162077Y-128083D01*
G01X166100Y-132500D02*
Y-127500D01*
X165340Y-128500D01*
G01Y-132500D02*
X166860D01*
G01X171960D02*
Y-127500D01*
X169617Y-131083D01*
X172783D01*
G01X191000Y-62500D02*
Y-137500D01*
G01Y-112500D02*
X294000D01*
Y-87500D01*
G01X191000D02*
X294000D01*
G01X301507Y-122500D02*
Y-117500D01*
X302773D01*
X303280Y-117750D01*
X303660Y-118083D01*
X303977Y-118583D01*
X304230Y-119167D01*
X304293Y-120000D01*
X304230Y-120833D01*
X303977Y-121417D01*
X303660Y-121917D01*
X303280Y-122250D01*
X302773Y-122500D01*
X301507D01*
G01X306417D02*
X308000Y-117500D01*
X309583Y-122500D01*
G01X309013Y-120750D02*
X306987D01*
G01X313100Y-117500D02*
Y-122500D01*
G01X311643Y-117500D02*
X314557D01*
G01X319467Y-122500D02*
X316933D01*
Y-117500D01*
X319467D01*
G01X318453Y-119917D02*
X316933D01*
G01X323300Y-122667D02*
X323173Y-122583D01*
Y-122417D01*
X323300Y-122333D01*
X323427Y-122417D01*
Y-122583D01*
X323300Y-122667D01*
G01Y-120417D02*
X323173Y-120333D01*
Y-120167D01*
X323300Y-120083D01*
X323427Y-120167D01*
Y-120333D01*
X323300Y-120417D01*
G01X296000Y-62500D02*
Y-137500D01*
G01X294000Y-62500D02*
Y-137500D01*
G01X301633Y-97500D02*
Y-92500D01*
X303153D01*
X303660Y-92750D01*
X304040Y-93333D01*
X304167Y-94000D01*
X304040Y-94667D01*
X303723Y-95167D01*
X303153Y-95417D01*
X301633D01*
G01X306860Y-97667D02*
X309140Y-92500D01*
G01X311643Y-97500D02*
Y-92500D01*
X314557Y-97500D01*
Y-92500D01*
G01X318200Y-97667D02*
X318073Y-97583D01*
Y-97417D01*
X318200Y-97333D01*
X318327Y-97417D01*
Y-97583D01*
X318200Y-97667D01*
G01Y-95417D02*
X318073Y-95333D01*
Y-95167D01*
X318200Y-95083D01*
X318327Y-95167D01*
Y-95333D01*
X318200Y-95417D01*
G01X296000Y-112500D02*
X496000D01*
G01X301633Y-72500D02*
Y-67500D01*
X303153D01*
X303660Y-67750D01*
X304040Y-68333D01*
X304167Y-69000D01*
X304040Y-69667D01*
X303723Y-70167D01*
X303153Y-70417D01*
X301633D01*
G01X306733Y-72500D02*
Y-67500D01*
X308317D01*
X308823Y-67750D01*
X309140Y-68083D01*
X309267Y-68750D01*
X309140Y-69417D01*
X308760Y-69833D01*
X308317Y-70083D01*
X306733D01*
G01X308317D02*
X309267Y-72500D01*
G01X313100D02*
X312593Y-72417D01*
X312150Y-72083D01*
X311770Y-71583D01*
X311517Y-71000D01*
X311390Y-70333D01*
Y-69667D01*
X311517Y-69000D01*
X311770Y-68417D01*
X312150Y-67917D01*
X312593Y-67583D01*
X313100Y-67500D01*
X313607Y-67583D01*
X314050Y-67917D01*
X314430Y-68417D01*
X314683Y-69000D01*
X314810Y-69667D01*
Y-70333D01*
X314683Y-71000D01*
X314430Y-71583D01*
X314050Y-72083D01*
X313607Y-72417D01*
X313100Y-72500D01*
G01X316933Y-71500D02*
X317250Y-72000D01*
X317630Y-72333D01*
X318073Y-72500D01*
X318580Y-72333D01*
X318960Y-72000D01*
X319340Y-71500D01*
X319467Y-70833D01*
Y-67500D01*
G01X324567Y-72500D02*
X322033D01*
Y-67500D01*
X324567D01*
G01X323553Y-69917D02*
X322033D01*
G01X329793Y-67917D02*
X329413Y-67667D01*
X328970Y-67500D01*
X328463D01*
X327893Y-67750D01*
X327450Y-68167D01*
X327133Y-68667D01*
X326880Y-69500D01*
X326817Y-70250D01*
X326943Y-71000D01*
X327133Y-71500D01*
X327513Y-72000D01*
X327957Y-72333D01*
X328400Y-72500D01*
X328843D01*
X329287Y-72333D01*
X329667Y-72083D01*
X329983Y-71750D01*
G01X333500Y-67500D02*
Y-72500D01*
G01X332043Y-67500D02*
X334957D01*
G01X338600Y-72667D02*
X338473Y-72583D01*
Y-72417D01*
X338600Y-72333D01*
X338727Y-72417D01*
Y-72583D01*
X338600Y-72667D01*
G01Y-70417D02*
X338473Y-70333D01*
Y-70167D01*
X338600Y-70083D01*
X338727Y-70167D01*
Y-70333D01*
X338600Y-70417D01*
G01X296000Y-87500D02*
X496000D01*
G01X411000Y-112500D02*
Y-137500D01*
G01X416633Y-122500D02*
Y-117500D01*
X418217D01*
X418723Y-117750D01*
X419040Y-118083D01*
X419167Y-118750D01*
X419040Y-119417D01*
X418660Y-119833D01*
X418217Y-120083D01*
X416633D01*
G01X418217D02*
X419167Y-122500D01*
G01X424267D02*
X421733D01*
Y-117500D01*
X424267D01*
G01X423253Y-119917D02*
X421733D01*
G01X426517Y-117500D02*
X428100Y-122500D01*
X429683Y-117500D01*
G01X433200Y-122667D02*
X433073Y-122583D01*
Y-122417D01*
X433200Y-122333D01*
X433327Y-122417D01*
Y-122583D01*
X433200Y-122667D01*
G01Y-120417D02*
X433073Y-120333D01*
Y-120167D01*
X433200Y-120083D01*
X433327Y-120167D01*
Y-120333D01*
X433200Y-120417D01*
G01X460000Y-112500D02*
Y-137500D01*
G01X-723776Y2987387D02*
Y-376795D01*
Y-489221D01*
X1782976D01*
Y-376795D01*
Y2987387D01*
X-723776D01*
G01X6705Y-124160D02*
X7332Y-124685D01*
X8037Y-125000D01*
X8663D01*
X9290Y-124685D01*
X9760Y-124160D01*
X9995Y-123425D01*
X9838Y-122690D01*
X9447Y-122060D01*
X8742Y-121640D01*
X7802Y-121430D01*
X7253Y-121010D01*
X7018Y-120275D01*
X7175Y-119540D01*
X7567Y-119015D01*
X8115Y-118700D01*
X8663D01*
X9212Y-118910D01*
X9682Y-119435D01*
G01X13005Y-125000D02*
Y-118700D01*
G01X16295D02*
Y-125000D01*
G01Y-121850D02*
X13005D01*
G01X20010Y-118700D02*
X21890D01*
G01X20950D02*
Y-125000D01*
G01X20010D02*
X21890D01*
G01X28817D02*
X25683D01*
Y-118700D01*
X28817D01*
G01X27563Y-121745D02*
X25683D01*
G01X31748Y-125000D02*
Y-118700D01*
X35352Y-125000D01*
Y-118700D01*
G01X39693Y-126155D02*
X40007Y-124790D01*
G01X46150Y-118700D02*
Y-125000D01*
G01X44348Y-118700D02*
X47952D01*
G01X50492Y-125000D02*
X52450Y-118700D01*
X54408Y-125000D01*
G01X53703Y-122795D02*
X51197D01*
G01X57810Y-118700D02*
X59690D01*
G01X58750D02*
Y-125000D01*
G01X57810D02*
X59690D01*
G01X62700Y-118700D02*
X63797Y-125000D01*
X65050Y-118700D01*
X66303Y-125000D01*
X67400Y-118700D01*
G01X69392Y-125000D02*
X71350Y-118700D01*
X73308Y-125000D01*
G01X72603Y-122795D02*
X70097D01*
G01X75848Y-125000D02*
Y-118700D01*
X79452Y-125000D01*
Y-118700D01*
G01X88683Y-125000D02*
Y-118700D01*
X90642D01*
X91268Y-119015D01*
X91660Y-119435D01*
X91817Y-120275D01*
X91660Y-121115D01*
X91190Y-121640D01*
X90642Y-121955D01*
X88683D01*
G01X90642D02*
X91817Y-125000D01*
G01X96550Y-125210D02*
X96393Y-125105D01*
Y-124895D01*
X96550Y-124790D01*
X96707Y-124895D01*
Y-125105D01*
X96550Y-125210D01*
G01X102850Y-125000D02*
X102223Y-124895D01*
X101675Y-124475D01*
X101205Y-123845D01*
X100892Y-123110D01*
X100735Y-122270D01*
Y-121430D01*
X100892Y-120590D01*
X101205Y-119855D01*
X101675Y-119225D01*
X102223Y-118805D01*
X102850Y-118700D01*
X103477Y-118805D01*
X104025Y-119225D01*
X104495Y-119855D01*
X104808Y-120590D01*
X104965Y-121430D01*
Y-122270D01*
X104808Y-123110D01*
X104495Y-123845D01*
X104025Y-124475D01*
X103477Y-124895D01*
X102850Y-125000D01*
G01X109150Y-125210D02*
X108993Y-125105D01*
Y-124895D01*
X109150Y-124790D01*
X109307Y-124895D01*
Y-125105D01*
X109150Y-125210D01*
G01X117173Y-119225D02*
X116703Y-118910D01*
X116155Y-118700D01*
X115528D01*
X114823Y-119015D01*
X114275Y-119540D01*
X113883Y-120170D01*
X113570Y-121220D01*
X113492Y-122165D01*
X113648Y-123110D01*
X113883Y-123740D01*
X114353Y-124370D01*
X114902Y-124790D01*
X115450Y-125000D01*
X115998D01*
X116547Y-124790D01*
X117017Y-124475D01*
X117408Y-124055D01*
G01X121750Y-125210D02*
X121593Y-125105D01*
Y-124895D01*
X121750Y-124790D01*
X121907Y-124895D01*
Y-125105D01*
X121750Y-125210D01*
G01X6627Y-115000D02*
Y-108700D01*
G01X9603D02*
X6627Y-112585D01*
G01X10073Y-115000D02*
X7958Y-110800D01*
G01X12927Y-108700D02*
Y-113215D01*
X13240Y-114160D01*
X13867Y-114790D01*
X14650Y-115000D01*
X15433Y-114790D01*
X16060Y-114160D01*
X16373Y-113215D01*
Y-108700D01*
G01X22517Y-115000D02*
X19383D01*
Y-108700D01*
X22517D01*
G01X21263Y-111745D02*
X19383D01*
G01X26310Y-108700D02*
X28190D01*
G01X27250D02*
Y-115000D01*
G01X26310D02*
X28190D01*
G01X38205Y-114160D02*
X38832Y-114685D01*
X39537Y-115000D01*
X40163D01*
X40790Y-114685D01*
X41260Y-114160D01*
X41495Y-113425D01*
X41338Y-112690D01*
X40947Y-112060D01*
X40242Y-111640D01*
X39302Y-111430D01*
X38753Y-111010D01*
X38518Y-110275D01*
X38675Y-109540D01*
X39067Y-109015D01*
X39615Y-108700D01*
X40163D01*
X40712Y-108910D01*
X41182Y-109435D01*
G01X44505Y-115000D02*
Y-108700D01*
G01X47795D02*
Y-115000D01*
G01Y-111850D02*
X44505D01*
G01X50492Y-115000D02*
X52450Y-108700D01*
X54408Y-115000D01*
G01X53703Y-112795D02*
X51197D01*
G01X56948Y-115000D02*
Y-108700D01*
X60552Y-115000D01*
Y-108700D01*
G01X69705Y-115000D02*
Y-108700D01*
G01X72995D02*
Y-115000D01*
G01Y-111850D02*
X69705D01*
G01X76005Y-114160D02*
X76632Y-114685D01*
X77337Y-115000D01*
X77963D01*
X78590Y-114685D01*
X79060Y-114160D01*
X79295Y-113425D01*
X79138Y-112690D01*
X78747Y-112060D01*
X78042Y-111640D01*
X77102Y-111430D01*
X76553Y-111010D01*
X76318Y-110275D01*
X76475Y-109540D01*
X76867Y-109015D01*
X77415Y-108700D01*
X77963D01*
X78512Y-108910D01*
X78982Y-109435D01*
G01X83010Y-108700D02*
X84890D01*
G01X83950D02*
Y-115000D01*
G01X83010D02*
X84890D01*
G01X88292D02*
X90250Y-108700D01*
X92208Y-115000D01*
G01X91503Y-112795D02*
X88997D01*
G01X94748Y-115000D02*
Y-108700D01*
X98352Y-115000D01*
Y-108700D01*
G01X103320Y-111850D02*
X104887D01*
Y-113740D01*
X104417Y-114370D01*
X103868Y-114790D01*
X103085Y-115000D01*
X102302Y-114790D01*
X101753Y-114370D01*
X101283Y-113740D01*
X100970Y-113005D01*
X100813Y-112165D01*
Y-111430D01*
X100970Y-110800D01*
X101283Y-110065D01*
X101753Y-109435D01*
X102223Y-109015D01*
X102850Y-108700D01*
X103398D01*
X104025Y-108910D01*
X104495Y-109330D01*
G01X108993Y-116155D02*
X109307Y-114790D01*
G01X115450Y-108700D02*
Y-115000D01*
G01X113648Y-108700D02*
X117252D01*
G01X119792Y-115000D02*
X121750Y-108700D01*
X123708Y-115000D01*
G01X123003Y-112795D02*
X120497D01*
G01X128050Y-115000D02*
X127423Y-114895D01*
X126875Y-114475D01*
X126405Y-113845D01*
X126092Y-113110D01*
X125935Y-112270D01*
Y-111430D01*
X126092Y-110590D01*
X126405Y-109855D01*
X126875Y-109225D01*
X127423Y-108805D01*
X128050Y-108700D01*
X128677Y-108805D01*
X129225Y-109225D01*
X129695Y-109855D01*
X130008Y-110590D01*
X130165Y-111430D01*
Y-112270D01*
X130008Y-113110D01*
X129695Y-113845D01*
X129225Y-114475D01*
X128677Y-114895D01*
X128050Y-115000D01*
G01X140650D02*
Y-112165D01*
X139083Y-108700D01*
G01X142217D02*
X140650Y-112165D01*
G01X145227Y-108700D02*
Y-113215D01*
X145540Y-114160D01*
X146167Y-114790D01*
X146950Y-115000D01*
X147733Y-114790D01*
X148360Y-114160D01*
X148673Y-113215D01*
Y-108700D01*
G01X151292Y-115000D02*
X153250Y-108700D01*
X155208Y-115000D01*
G01X154503Y-112795D02*
X151997D01*
G01X157748Y-115000D02*
Y-108700D01*
X161352Y-115000D01*
Y-108700D01*
G01X30650Y-92300D02*
X28130Y-91883D01*
X25925Y-90217D01*
X24035Y-87717D01*
X22775Y-84800D01*
X22145Y-81467D01*
Y-78133D01*
X22775Y-74800D01*
X24035Y-71883D01*
X25925Y-69384D01*
X28130Y-67717D01*
X30650Y-67300D01*
X33170Y-67717D01*
X35375Y-69384D01*
X37265Y-71883D01*
X38525Y-74800D01*
X39155Y-78133D01*
Y-81467D01*
X38525Y-84800D01*
X37265Y-87717D01*
X35375Y-90217D01*
X33170Y-91883D01*
X30650Y-92300D01*
G01X33170Y-85633D02*
X36950Y-92300D01*
G01X50495Y-75634D02*
Y-87300D01*
X51755Y-90217D01*
X53645Y-91883D01*
X55850Y-92300D01*
X58055Y-91883D01*
X59945Y-90217D01*
X61205Y-87300D01*
G01Y-92300D02*
Y-75634D01*
G01X86720Y-92300D02*
Y-75634D01*
G01Y-78550D02*
X85460Y-76884D01*
X83570Y-76050D01*
X81365Y-75634D01*
X79160Y-76467D01*
X77270Y-78133D01*
X76010Y-80634D01*
X75380Y-83967D01*
X76010Y-87300D01*
X77270Y-89801D01*
X79160Y-91467D01*
X81365Y-92300D01*
X83570Y-91883D01*
X85460Y-90634D01*
X86720Y-88967D01*
G01X100895Y-92300D02*
Y-75634D01*
G01Y-79800D02*
X102155Y-77717D01*
X104045Y-76050D01*
X106565Y-75634D01*
X108770Y-76050D01*
X110660Y-77717D01*
X111605Y-80634D01*
Y-92300D01*
G01X131450Y-67300D02*
Y-92300D01*
G01X127040Y-75634D02*
X135860D01*
G01X162320Y-92300D02*
Y-75634D01*
G01Y-78550D02*
X161060Y-76884D01*
X159170Y-76050D01*
X156965Y-75634D01*
X154760Y-76467D01*
X152870Y-78133D01*
X151610Y-80634D01*
X150980Y-83967D01*
X151610Y-87300D01*
X152870Y-89801D01*
X154760Y-91467D01*
X156965Y-92300D01*
X159170Y-91883D01*
X161060Y-90634D01*
X162320Y-88967D01*
G01X6548Y-105000D02*
Y-98700D01*
X10152Y-105000D01*
Y-98700D01*
G01X14650Y-105000D02*
X14023Y-104895D01*
X13475Y-104475D01*
X13005Y-103845D01*
X12692Y-103110D01*
X12535Y-102270D01*
Y-101430D01*
X12692Y-100590D01*
X13005Y-99855D01*
X13475Y-99225D01*
X14023Y-98805D01*
X14650Y-98700D01*
X15277Y-98805D01*
X15825Y-99225D01*
X16295Y-99855D01*
X16608Y-100590D01*
X16765Y-101430D01*
Y-102270D01*
X16608Y-103110D01*
X16295Y-103845D01*
X15825Y-104475D01*
X15277Y-104895D01*
X14650Y-105000D01*
G01X20950Y-105210D02*
X20793Y-105105D01*
Y-104895D01*
X20950Y-104790D01*
X21107Y-104895D01*
Y-105105D01*
X20950Y-105210D01*
G01X27250Y-105000D02*
Y-98700D01*
X26310Y-99960D01*
G01Y-105000D02*
X28190D01*
G01X33550D02*
X34098Y-104895D01*
X34725Y-104580D01*
X35117Y-104055D01*
X35273Y-103320D01*
X35117Y-102585D01*
X34647Y-101955D01*
X33942Y-101640D01*
X33158D01*
X32688Y-101430D01*
X32297Y-100905D01*
X32140Y-100170D01*
X32375Y-99435D01*
X32923Y-98910D01*
X33550Y-98700D01*
X34177Y-98910D01*
X34725Y-99435D01*
X34960Y-100170D01*
X34803Y-100905D01*
X34412Y-101430D01*
X33942Y-101640D01*
X33158D01*
X32453Y-101955D01*
X31983Y-102585D01*
X31827Y-103320D01*
X31983Y-104055D01*
X32375Y-104580D01*
X33002Y-104895D01*
X33550Y-105000D01*
G01X39850D02*
X40398Y-104895D01*
X41025Y-104580D01*
X41417Y-104055D01*
X41573Y-103320D01*
X41417Y-102585D01*
X40947Y-101955D01*
X40242Y-101640D01*
X39458D01*
X38988Y-101430D01*
X38597Y-100905D01*
X38440Y-100170D01*
X38675Y-99435D01*
X39223Y-98910D01*
X39850Y-98700D01*
X40477Y-98910D01*
X41025Y-99435D01*
X41260Y-100170D01*
X41103Y-100905D01*
X40712Y-101430D01*
X40242Y-101640D01*
X39458D01*
X38753Y-101955D01*
X38283Y-102585D01*
X38127Y-103320D01*
X38283Y-104055D01*
X38675Y-104580D01*
X39302Y-104895D01*
X39850Y-105000D01*
G01X45993Y-106155D02*
X46307Y-104790D01*
G01X50100Y-98700D02*
X51197Y-105000D01*
X52450Y-98700D01*
X53703Y-105000D01*
X54800Y-98700D01*
G01X60317Y-105000D02*
X57183D01*
Y-98700D01*
X60317D01*
G01X59063Y-101745D02*
X57183D01*
G01X63248Y-105000D02*
Y-98700D01*
X66852Y-105000D01*
Y-98700D01*
G01X76005Y-105000D02*
Y-98700D01*
G01X79295D02*
Y-105000D01*
G01Y-101850D02*
X76005D01*
G01X81600Y-98700D02*
X82697Y-105000D01*
X83950Y-98700D01*
X85203Y-105000D01*
X86300Y-98700D01*
G01X88292Y-105000D02*
X90250Y-98700D01*
X92208Y-105000D01*
G01X91503Y-102795D02*
X88997D01*
G01X101362Y-99750D02*
X101832Y-99120D01*
X102380Y-98805D01*
X103007Y-98700D01*
X103790Y-98910D01*
X104338Y-99435D01*
X104495Y-100065D01*
X104417Y-100695D01*
X104103Y-101220D01*
X102537Y-102270D01*
X101832Y-103005D01*
X101362Y-104055D01*
X101205Y-105000D01*
X104495D01*
G01X107348D02*
Y-98700D01*
X110952Y-105000D01*
Y-98700D01*
G01X113727Y-105000D02*
Y-98700D01*
X115293D01*
X115920Y-99015D01*
X116390Y-99435D01*
X116782Y-100065D01*
X117095Y-100800D01*
X117173Y-101850D01*
X117095Y-102900D01*
X116782Y-103635D01*
X116390Y-104265D01*
X115920Y-104685D01*
X115293Y-105000D01*
X113727D01*
G01X126483D02*
Y-98700D01*
X128442D01*
X129068Y-99015D01*
X129460Y-99435D01*
X129617Y-100275D01*
X129460Y-101115D01*
X128990Y-101640D01*
X128442Y-101955D01*
X126483D01*
G01X128442D02*
X129617Y-105000D01*
G01X132627D02*
Y-98700D01*
X134193D01*
X134820Y-99015D01*
X135290Y-99435D01*
X135682Y-100065D01*
X135995Y-100800D01*
X136073Y-101850D01*
X135995Y-102900D01*
X135682Y-103635D01*
X135290Y-104265D01*
X134820Y-104685D01*
X134193Y-105000D01*
X132627D01*
G01X140650Y-105210D02*
X140493Y-105105D01*
Y-104895D01*
X140650Y-104790D01*
X140807Y-104895D01*
Y-105105D01*
X140650Y-105210D01*
G01X202000Y-72000D02*
Y-80000D01*
X206000D01*
G01X213800D02*
Y-74667D01*
G01Y-75600D02*
X213400Y-75067D01*
X212800Y-74800D01*
X212100Y-74667D01*
X211400Y-74933D01*
X210800Y-75467D01*
X210400Y-76267D01*
X210200Y-77333D01*
X210400Y-78400D01*
X210800Y-79200D01*
X211400Y-79733D01*
X212100Y-80000D01*
X212800Y-79867D01*
X213400Y-79467D01*
X213800Y-78934D01*
G01X217900Y-82400D02*
X218500Y-82667D01*
X219300Y-82400D01*
X219800Y-81867D01*
X220200Y-81200D01*
X220800Y-79067D01*
X222100Y-74667D01*
G01X218900D02*
X220800Y-79067D01*
G01X226500Y-76400D02*
X229700D01*
X229400Y-75467D01*
X228900Y-74933D01*
X228200Y-74667D01*
X227500Y-74800D01*
X226900Y-75200D01*
X226500Y-76133D01*
X226300Y-76934D01*
Y-77733D01*
X226500Y-78533D01*
X227000Y-79333D01*
X227600Y-79867D01*
X228300Y-80000D01*
X229000Y-79733D01*
X229700Y-78934D01*
G01X234600Y-80000D02*
Y-74667D01*
G01Y-75733D02*
X235100Y-75200D01*
X235600Y-74800D01*
X236300Y-74667D01*
X236800Y-74800D01*
X237400Y-75200D01*
G01X223400Y-128934D02*
X224200Y-129600D01*
X225100Y-130000D01*
X225900D01*
X226700Y-129600D01*
X227300Y-128934D01*
X227600Y-128000D01*
X227400Y-127067D01*
X226900Y-126267D01*
X226000Y-125733D01*
X224800Y-125467D01*
X224100Y-124933D01*
X223800Y-124000D01*
X224000Y-123067D01*
X224500Y-122400D01*
X225200Y-122000D01*
X225900D01*
X226600Y-122267D01*
X227200Y-122933D01*
G01X235300Y-130000D02*
Y-124667D01*
G01Y-125600D02*
X234900Y-125067D01*
X234300Y-124800D01*
X233600Y-124667D01*
X232900Y-124933D01*
X232300Y-125467D01*
X231900Y-126267D01*
X231700Y-127333D01*
X231900Y-128400D01*
X232300Y-129200D01*
X232900Y-129733D01*
X233600Y-130000D01*
X234300Y-129867D01*
X234900Y-129467D01*
X235300Y-128934D01*
G01X239800Y-130000D02*
Y-124667D01*
G01Y-126000D02*
X240200Y-125333D01*
X240800Y-124800D01*
X241600Y-124667D01*
X242300Y-124800D01*
X242900Y-125333D01*
X243200Y-126267D01*
Y-130000D01*
G01X251300Y-122000D02*
Y-130000D01*
G01Y-128800D02*
X250900Y-129467D01*
X250300Y-129867D01*
X249600Y-130000D01*
X248800Y-129733D01*
X248200Y-129067D01*
X247800Y-128267D01*
X247700Y-127333D01*
X247800Y-126400D01*
X248200Y-125600D01*
X248800Y-124933D01*
X249600Y-124667D01*
X250300Y-124800D01*
X250800Y-125067D01*
X251300Y-125600D01*
G01X255400Y-132400D02*
X256000Y-132667D01*
X256800Y-132400D01*
X257300Y-131867D01*
X257700Y-131200D01*
X258300Y-129067D01*
X259600Y-124667D01*
G01X256400D02*
X258300Y-129067D01*
G01X231800Y-97000D02*
X234200D01*
G01X233000D02*
Y-105000D01*
G01X231800D02*
X234200D01*
G01X238700D02*
Y-97000D01*
X243300Y-105000D01*
Y-97000D01*
G01X249000Y-105000D02*
Y-97000D01*
X247800Y-98600D01*
G01Y-105000D02*
X250200D01*
G01X253300Y-78400D02*
X253900Y-79333D01*
X254700Y-79867D01*
X255600Y-80000D01*
X256400Y-79867D01*
X257200Y-79200D01*
X257700Y-78400D01*
X257800Y-77600D01*
X257600Y-76667D01*
X256900Y-76000D01*
X256200Y-75733D01*
X255300D01*
G01X256200D02*
X256800Y-75333D01*
X257300Y-74667D01*
X257500Y-73867D01*
X257300Y-73067D01*
X256800Y-72400D01*
X255900Y-72000D01*
X255000Y-72133D01*
X254100Y-72667D01*
G01X328600Y-123333D02*
X329200Y-122533D01*
X329900Y-122133D01*
X330700Y-122000D01*
X331700Y-122267D01*
X332400Y-122933D01*
X332600Y-123733D01*
X332500Y-124534D01*
X332100Y-125200D01*
X330100Y-126533D01*
X329200Y-127467D01*
X328600Y-128800D01*
X328400Y-130000D01*
X332600D01*
G01X338500Y-122000D02*
X337700Y-122267D01*
X337100Y-122933D01*
X336700Y-123733D01*
X336400Y-124800D01*
X336300Y-126000D01*
X336400Y-127200D01*
X336700Y-128267D01*
X337100Y-129067D01*
X337700Y-129733D01*
X338500Y-130000D01*
X339300Y-129733D01*
X339900Y-129067D01*
X340300Y-128267D01*
X340600Y-127200D01*
X340700Y-126000D01*
X340600Y-124800D01*
X340300Y-123733D01*
X339900Y-122933D01*
X339300Y-122267D01*
X338500Y-122000D01*
G01X346500Y-130000D02*
Y-122000D01*
X345300Y-123600D01*
G01Y-130000D02*
X347700D01*
G01X352600Y-123333D02*
X353200Y-122533D01*
X353900Y-122133D01*
X354700Y-122000D01*
X355700Y-122267D01*
X356400Y-122933D01*
X356600Y-123733D01*
X356500Y-124534D01*
X356100Y-125200D01*
X354100Y-126533D01*
X353200Y-127467D01*
X352600Y-128800D01*
X352400Y-130000D01*
X356600D01*
G01X360700Y-130267D02*
X364300Y-122000D01*
G01X370500D02*
X369700Y-122267D01*
X369100Y-122933D01*
X368700Y-123733D01*
X368400Y-124800D01*
X368300Y-126000D01*
X368400Y-127200D01*
X368700Y-128267D01*
X369100Y-129067D01*
X369700Y-129733D01*
X370500Y-130000D01*
X371300Y-129733D01*
X371900Y-129067D01*
X372300Y-128267D01*
X372600Y-127200D01*
X372700Y-126000D01*
X372600Y-124800D01*
X372300Y-123733D01*
X371900Y-122933D01*
X371300Y-122267D01*
X370500Y-122000D01*
G01X376800Y-129067D02*
X377500Y-129733D01*
X378300Y-130000D01*
X379100Y-129733D01*
X379800Y-128934D01*
X380300Y-127733D01*
X380500Y-126533D01*
Y-125067D01*
X380300Y-123867D01*
X379800Y-122800D01*
X379200Y-122267D01*
X378500Y-122000D01*
X377700Y-122267D01*
X377100Y-122800D01*
X376700Y-123600D01*
X376500Y-124667D01*
X376700Y-125600D01*
X377200Y-126533D01*
X377800Y-127067D01*
X378500Y-127200D01*
X379300Y-126934D01*
X379900Y-126267D01*
X380500Y-125067D01*
G01X384700Y-130267D02*
X388300Y-122000D01*
G01X392600Y-123333D02*
X393200Y-122533D01*
X393900Y-122133D01*
X394700Y-122000D01*
X395700Y-122267D01*
X396400Y-122933D01*
X396600Y-123733D01*
X396500Y-124534D01*
X396100Y-125200D01*
X394100Y-126533D01*
X393200Y-127467D01*
X392600Y-128800D01*
X392400Y-130000D01*
X396600D01*
G01X402500D02*
X403200Y-129867D01*
X404000Y-129467D01*
X404500Y-128800D01*
X404700Y-127867D01*
X404500Y-126934D01*
X403900Y-126133D01*
X403000Y-125733D01*
X402000D01*
X401400Y-125467D01*
X400900Y-124800D01*
X400700Y-123867D01*
X401000Y-122933D01*
X401700Y-122267D01*
X402500Y-122000D01*
X403300Y-122267D01*
X404000Y-122933D01*
X404300Y-123867D01*
X404100Y-124800D01*
X403600Y-125467D01*
X403000Y-125733D01*
X402000D01*
X401100Y-126133D01*
X400500Y-126934D01*
X400300Y-127867D01*
X400500Y-128800D01*
X401000Y-129467D01*
X401800Y-129867D01*
X402500Y-130000D01*
G01X328300Y-105000D02*
Y-97000D01*
X330300D01*
X331100Y-97400D01*
X331700Y-97933D01*
X332200Y-98733D01*
X332600Y-99667D01*
X332700Y-101000D01*
X332600Y-102333D01*
X332200Y-103267D01*
X331700Y-104067D01*
X331100Y-104600D01*
X330300Y-105000D01*
X328300D01*
G01X336000D02*
X338500Y-97000D01*
X341000Y-105000D01*
G01X340100Y-102200D02*
X336900D01*
G01X346500Y-97000D02*
X345700Y-97267D01*
X345100Y-97933D01*
X344700Y-98733D01*
X344400Y-99800D01*
X344300Y-101000D01*
X344400Y-102200D01*
X344700Y-103267D01*
X345100Y-104067D01*
X345700Y-104733D01*
X346500Y-105000D01*
X347300Y-104733D01*
X347900Y-104067D01*
X348300Y-103267D01*
X348600Y-102200D01*
X348700Y-101000D01*
X348600Y-99800D01*
X348300Y-98733D01*
X347900Y-97933D01*
X347300Y-97267D01*
X346500Y-97000D01*
G01X354500D02*
Y-105000D01*
G01X352200Y-97000D02*
X356800D01*
G01X360600Y-101667D02*
X361300Y-100733D01*
X361900Y-100200D01*
X362700Y-99933D01*
X363400Y-100200D01*
X363900Y-100733D01*
X364300Y-101533D01*
X364400Y-102467D01*
X364300Y-103267D01*
X363900Y-104067D01*
X363300Y-104733D01*
X362600Y-105000D01*
X361800Y-104733D01*
X361100Y-103934D01*
X360700Y-102733D01*
X360600Y-101400D01*
X360800Y-99667D01*
X361100Y-98733D01*
X361600Y-97800D01*
X362300Y-97133D01*
X363000Y-97000D01*
X363700Y-97267D01*
X364200Y-97933D01*
G01X367900Y-105000D02*
Y-97000D01*
X370500Y-103667D01*
X373100Y-97000D01*
Y-105000D01*
G01X378500Y-97000D02*
Y-105000D01*
G01X376200Y-97000D02*
X380800D01*
G01X387300Y-100733D02*
X387700Y-100333D01*
X388000Y-99667D01*
X388200Y-98733D01*
X388000Y-97933D01*
X387600Y-97400D01*
X386900Y-97000D01*
X384200D01*
Y-105000D01*
X387500D01*
X388200Y-104467D01*
X388600Y-103667D01*
X388800Y-102733D01*
X388600Y-101800D01*
X388000Y-101000D01*
X387300Y-100733D01*
X384200D01*
G01X394500Y-105000D02*
X395200Y-104867D01*
X396000Y-104467D01*
X396500Y-103800D01*
X396700Y-102867D01*
X396500Y-101934D01*
X395900Y-101133D01*
X395000Y-100733D01*
X394000D01*
X393400Y-100467D01*
X392900Y-99800D01*
X392700Y-98867D01*
X393000Y-97933D01*
X393700Y-97267D01*
X394500Y-97000D01*
X395300Y-97267D01*
X396000Y-97933D01*
X396300Y-98867D01*
X396100Y-99800D01*
X395600Y-100467D01*
X395000Y-100733D01*
X394000D01*
X393100Y-101133D01*
X392500Y-101934D01*
X392300Y-102867D01*
X392500Y-103800D01*
X393000Y-104467D01*
X393800Y-104867D01*
X394500Y-105000D01*
G01X400300D02*
Y-97000D01*
X402300D01*
X403100Y-97400D01*
X403700Y-97933D01*
X404200Y-98733D01*
X404600Y-99667D01*
X404700Y-101000D01*
X404600Y-102333D01*
X404200Y-103267D01*
X403700Y-104067D01*
X403100Y-104600D01*
X402300Y-105000D01*
X400300D01*
G01X410500Y-97000D02*
X409700Y-97267D01*
X409100Y-97933D01*
X408700Y-98733D01*
X408400Y-99800D01*
X408300Y-101000D01*
X408400Y-102200D01*
X408700Y-103267D01*
X409100Y-104067D01*
X409700Y-104733D01*
X410500Y-105000D01*
X411300Y-104733D01*
X411900Y-104067D01*
X412300Y-103267D01*
X412600Y-102200D01*
X412700Y-101000D01*
X412600Y-99800D01*
X412300Y-98733D01*
X411900Y-97933D01*
X411300Y-97267D01*
X410500Y-97000D01*
G01X350500Y-72000D02*
Y-80000D01*
G01X348200Y-72000D02*
X352800D01*
G01X356600Y-76667D02*
X357300Y-75733D01*
X357900Y-75200D01*
X358700Y-74933D01*
X359400Y-75200D01*
X359900Y-75733D01*
X360300Y-76533D01*
X360400Y-77467D01*
X360300Y-78267D01*
X359900Y-79067D01*
X359300Y-79733D01*
X358600Y-80000D01*
X357800Y-79733D01*
X357100Y-78934D01*
X356700Y-77733D01*
X356600Y-76400D01*
X356800Y-74667D01*
X357100Y-73733D01*
X357600Y-72800D01*
X358300Y-72133D01*
X359000Y-72000D01*
X359700Y-72267D01*
X360200Y-72933D01*
G01X363900Y-80000D02*
Y-72000D01*
X366500Y-78667D01*
X369100Y-72000D01*
Y-80000D01*
G01X371500Y-82667D02*
X377500D01*
G01X380500Y-80000D02*
Y-72000D01*
X382900D01*
X383700Y-72400D01*
X384300Y-73333D01*
X384500Y-74400D01*
X384300Y-75467D01*
X383800Y-76267D01*
X382900Y-76667D01*
X380500D01*
G01X388300Y-80000D02*
Y-72000D01*
X390300D01*
X391100Y-72400D01*
X391700Y-72933D01*
X392200Y-73733D01*
X392600Y-74667D01*
X392700Y-76000D01*
X392600Y-77333D01*
X392200Y-78267D01*
X391700Y-79067D01*
X391100Y-79600D01*
X390300Y-80000D01*
X388300D01*
G01X399300Y-75733D02*
X399700Y-75333D01*
X400000Y-74667D01*
X400200Y-73733D01*
X400000Y-72933D01*
X399600Y-72400D01*
X398900Y-72000D01*
X396200D01*
Y-80000D01*
X399500D01*
X400200Y-79467D01*
X400600Y-78667D01*
X400800Y-77733D01*
X400600Y-76800D01*
X400000Y-76000D01*
X399300Y-75733D01*
X396200D01*
G01X403500Y-82667D02*
X409500D01*
G01X412300Y-80000D02*
Y-72000D01*
X414300D01*
X415100Y-72400D01*
X415700Y-72933D01*
X416200Y-73733D01*
X416600Y-74667D01*
X416700Y-76000D01*
X416600Y-77333D01*
X416200Y-78267D01*
X415700Y-79067D01*
X415100Y-79600D01*
X414300Y-80000D01*
X412300D01*
G01X419500Y-82667D02*
X425500D01*
G01X431300Y-75733D02*
X431700Y-75333D01*
X432000Y-74667D01*
X432200Y-73733D01*
X432000Y-72933D01*
X431600Y-72400D01*
X430900Y-72000D01*
X428200D01*
Y-80000D01*
X431500D01*
X432200Y-79467D01*
X432600Y-78667D01*
X432800Y-77733D01*
X432600Y-76800D01*
X432000Y-76000D01*
X431300Y-75733D01*
X428200D01*
G01X436300Y-80000D02*
Y-72000D01*
X438300D01*
X439100Y-72400D01*
X439700Y-72933D01*
X440200Y-73733D01*
X440600Y-74667D01*
X440700Y-76000D01*
X440600Y-77333D01*
X440200Y-78267D01*
X439700Y-79067D01*
X439100Y-79600D01*
X438300Y-80000D01*
X436300D01*
G01X443300Y-130000D02*
Y-122000D01*
X445300D01*
X446100Y-122400D01*
X446700Y-122933D01*
X447200Y-123733D01*
X447600Y-124667D01*
X447700Y-126000D01*
X447600Y-127333D01*
X447200Y-128267D01*
X446700Y-129067D01*
X446100Y-129600D01*
X445300Y-130000D01*
X443300D01*
G01X473000D02*
Y-122000D01*
X471800Y-123600D01*
G01Y-130000D02*
X474200D01*
G01X478800Y-128800D02*
X479400Y-129467D01*
X480100Y-129867D01*
X481000Y-130000D01*
X481900Y-129733D01*
X482600Y-129200D01*
X483100Y-128267D01*
X483200Y-127200D01*
X483000Y-126133D01*
X482500Y-125467D01*
X481800Y-124933D01*
X481100Y-124800D01*
X480400Y-124933D01*
X479500Y-125467D01*
X479800Y-122000D01*
X482500D01*
M02*
